G04 ================== begin FILE IDENTIFICATION RECORD ==================*
G04 Layout Name:  15669-1.brd*
G04 Film Name:    L7GND*
G04 File Format:  Gerber RS274X*
G04 File Origin:  Cadence Allegro 16.5-S056*
G04 Origin Date:  Wed Nov 16 04:08:58 2016*
G04 *
G04 Layer:  VIA CLASS/L7GND*
G04 Layer:  PIN/L7GND*
G04 Layer:  ETCH/L7GND*
G04 Layer:  DRAWING FORMAT/LAYER_PCB_STORY*
G04 Layer:  DRAWING FORMAT/LAYER_L7GND*
G04 *
G04 Offset:    (0.00 0.00)*
G04 Mirror:    No*
G04 Mode:      Negative*
G04 Rotation:  0*
G04 FullContactRelief:  No*
G04 UndefLineWidth:     6.00*
G04 ================== end FILE IDENTIFICATION RECORD ====================*
%FSLAX35Y35*MOIN*%
%IR0*IPPOS*OFA0.00000B0.00000*MIA0B0*SFA1.00000B1.00000*%
%ADD22O,.115X.072*%
%ADD16C,.03*%
%ADD17C,.032*%
%ADD21C,.036*%
%AMMACRO19*
4,1,15,.00398,.00044,
.003999,.000208,
.004004,-.000025,
.003996,-.000258,
.00398,-.00044,
.00483,-.00129,
.004897,-.001007,
.004947,-.000721,
.004981,-.000432,
.004997,-.000141,
.004997,.000149,
.00498,.00044,
.004946,.000729,
.004895,.001015,
.00483,.00129,
.00398,.00044,
90.*
4,1,15,.00044,-.00398,
.000208,-.003999,
-.000025,-.004004,
-.000258,-.003996,
-.00044,-.00398,
-.00129,-.00483,
-.001007,-.004897,
-.000721,-.004947,
-.000432,-.004981,
-.000141,-.004997,
.000149,-.004997,
.00044,-.00498,
.000729,-.004946,
.001015,-.004895,
.00129,-.00483,
.00044,-.00398,
90.*
4,1,15,-.00398,-.00044,
-.003999,-.000208,
-.004004,.000025,
-.003996,.000258,
-.00398,.00044,
-.00483,.00129,
-.004897,.001007,
-.004947,.000721,
-.004981,.000432,
-.004997,.000141,
-.004997,-.000149,
-.00498,-.00044,
-.004946,-.000729,
-.004895,-.001015,
-.00483,-.00129,
-.00398,-.00044,
90.*
4,1,15,-.00044,.00398,
-.000208,.003999,
.000025,.004004,
.000258,.003996,
.00044,.00398,
.00129,.00483,
.001007,.004897,
.000721,.004947,
.000432,.004981,
.000141,.004997,
-.000149,.004997,
-.00044,.00498,
-.000729,.004946,
-.001015,.004895,
-.00129,.00483,
-.00044,.00398,
90.*
%
%ADD19MACRO19*%
%AMMACRO11*
4,1,15,.00398,.00044,
.003999,.000208,
.004004,-.000025,
.003996,-.000258,
.00398,-.00044,
.00483,-.00129,
.004897,-.001007,
.004947,-.000721,
.004981,-.000432,
.004997,-.000141,
.004997,.000149,
.00498,.00044,
.004946,.000729,
.004895,.001015,
.00483,.00129,
.00398,.00044,
0.0*
4,1,15,.00044,-.00398,
.000208,-.003999,
-.000025,-.004004,
-.000258,-.003996,
-.00044,-.00398,
-.00129,-.00483,
-.001007,-.004897,
-.000721,-.004947,
-.000432,-.004981,
-.000141,-.004997,
.000149,-.004997,
.00044,-.00498,
.000729,-.004946,
.001015,-.004895,
.00129,-.00483,
.00044,-.00398,
0.0*
4,1,15,-.00398,-.00044,
-.003999,-.000208,
-.004004,.000025,
-.003996,.000258,
-.00398,.00044,
-.00483,.00129,
-.004897,.001007,
-.004947,.000721,
-.004981,.000432,
-.004997,.000141,
-.004997,-.000149,
-.00498,-.00044,
-.004946,-.000729,
-.004895,-.001015,
-.00483,-.00129,
-.00398,-.00044,
0.0*
4,1,15,-.00044,.00398,
-.000208,.003999,
.000025,.004004,
.000258,.003996,
.00044,.00398,
.00129,.00483,
.001007,.004897,
.000721,.004947,
.000432,.004981,
.000141,.004997,
-.000149,.004997,
-.00044,.00498,
-.000729,.004946,
-.001015,.004895,
-.00129,.00483,
-.00044,.00398,
0.0*
%
%ADD11MACRO11*%
%AMMACRO20*
4,1,15,-.00398,.00044,
-.003999,.000208,
-.004004,-.000025,
-.003996,-.000258,
-.00398,-.00044,
-.00483,-.00129,
-.004897,-.001007,
-.004947,-.000721,
-.004981,-.000432,
-.004997,-.000141,
-.004997,.000149,
-.00498,.00044,
-.004946,.000729,
-.004895,.001015,
-.00483,.00129,
-.00398,.00044,
0.0*
4,1,15,-.00044,-.00398,
-.000208,-.003999,
.000025,-.004004,
.000258,-.003996,
.00044,-.00398,
.00129,-.00483,
.001007,-.004897,
.000721,-.004947,
.000432,-.004981,
.000141,-.004997,
-.000149,-.004997,
-.00044,-.00498,
-.000729,-.004946,
-.001015,-.004895,
-.00129,-.00483,
-.00044,-.00398,
0.0*
4,1,15,.00398,-.00044,
.003999,-.000208,
.004004,.000025,
.003996,.000258,
.00398,.00044,
.00483,.00129,
.004897,.001007,
.004947,.000721,
.004981,.000432,
.004997,.000141,
.004997,-.000149,
.00498,-.00044,
.004946,-.000729,
.004895,-.001015,
.00483,-.00129,
.00398,-.00044,
0.0*
4,1,15,.00044,.00398,
.000208,.003999,
-.000025,.004004,
-.000258,.003996,
-.00044,.00398,
-.00129,.00483,
-.001007,.004897,
-.000721,.004947,
-.000432,.004981,
-.000141,.004997,
.000149,.004997,
.00044,.00498,
.000729,.004946,
.001015,.004895,
.00129,.00483,
.00044,.00398,
0.0*
%
%ADD20MACRO20*%
%ADD23C,.101*%
%ADD10C,.114*%
%ADD14C,.115*%
%ADD18C,.18*%
%ADD28C,.174*%
%AMMACRO27*
4,1,15,.00398,.00044,
.003999,.000208,
.004004,-.000025,
.003996,-.000258,
.00398,-.00044,
.00483,-.00129,
.004897,-.001007,
.004947,-.000721,
.004981,-.000432,
.004997,-.000141,
.004997,.000149,
.00498,.00044,
.004946,.000729,
.004895,.001015,
.00483,.00129,
.00398,.00044,
135.*
4,1,15,.00044,-.00398,
.000208,-.003999,
-.000025,-.004004,
-.000258,-.003996,
-.00044,-.00398,
-.00129,-.00483,
-.001007,-.004897,
-.000721,-.004947,
-.000432,-.004981,
-.000141,-.004997,
.000149,-.004997,
.00044,-.00498,
.000729,-.004946,
.001015,-.004895,
.00129,-.00483,
.00044,-.00398,
135.*
4,1,15,-.00398,-.00044,
-.003999,-.000208,
-.004004,.000025,
-.003996,.000258,
-.00398,.00044,
-.00483,.00129,
-.004897,.001007,
-.004947,.000721,
-.004981,.000432,
-.004997,.000141,
-.004997,-.000149,
-.00498,-.00044,
-.004946,-.000729,
-.004895,-.001015,
-.00483,-.00129,
-.00398,-.00044,
135.*
4,1,15,-.00044,.00398,
-.000208,.003999,
.000025,.004004,
.000258,.003996,
.00044,.00398,
.00129,.00483,
.001007,.004897,
.000721,.004947,
.000432,.004981,
.000141,.004997,
-.000149,.004997,
-.00044,.00498,
-.000729,.004946,
-.001015,.004895,
-.00129,.00483,
-.00044,.00398,
135.*
%
%ADD27MACRO27*%
%AMMACRO25*
4,1,15,.00398,.00044,
.003999,.000208,
.004004,-.000025,
.003996,-.000258,
.00398,-.00044,
.00483,-.00129,
.004897,-.001007,
.004947,-.000721,
.004981,-.000432,
.004997,-.000141,
.004997,.000149,
.00498,.00044,
.004946,.000729,
.004895,.001015,
.00483,.00129,
.00398,.00044,
270.*
4,1,15,.00044,-.00398,
.000208,-.003999,
-.000025,-.004004,
-.000258,-.003996,
-.00044,-.00398,
-.00129,-.00483,
-.001007,-.004897,
-.000721,-.004947,
-.000432,-.004981,
-.000141,-.004997,
.000149,-.004997,
.00044,-.00498,
.000729,-.004946,
.001015,-.004895,
.00129,-.00483,
.00044,-.00398,
270.*
4,1,15,-.00398,-.00044,
-.003999,-.000208,
-.004004,.000025,
-.003996,.000258,
-.00398,.00044,
-.00483,.00129,
-.004897,.001007,
-.004947,.000721,
-.004981,.000432,
-.004997,.000141,
-.004997,-.000149,
-.00498,-.00044,
-.004946,-.000729,
-.004895,-.001015,
-.00483,-.00129,
-.00398,-.00044,
270.*
4,1,15,-.00044,.00398,
-.000208,.003999,
.000025,.004004,
.000258,.003996,
.00044,.00398,
.00129,.00483,
.001007,.004897,
.000721,.004947,
.000432,.004981,
.000141,.004997,
-.000149,.004997,
-.00044,.00498,
-.000729,.004946,
-.001015,.004895,
-.00129,.00483,
-.00044,.00398,
270.*
%
%ADD25MACRO25*%
%AMMACRO24*
4,1,15,.00398,.00044,
.003999,.000208,
.004004,-.000025,
.003996,-.000258,
.00398,-.00044,
.00483,-.00129,
.004897,-.001007,
.004947,-.000721,
.004981,-.000432,
.004997,-.000141,
.004997,.000149,
.00498,.00044,
.004946,.000729,
.004895,.001015,
.00483,.00129,
.00398,.00044,
315.*
4,1,15,.00044,-.00398,
.000208,-.003999,
-.000025,-.004004,
-.000258,-.003996,
-.00044,-.00398,
-.00129,-.00483,
-.001007,-.004897,
-.000721,-.004947,
-.000432,-.004981,
-.000141,-.004997,
.000149,-.004997,
.00044,-.00498,
.000729,-.004946,
.001015,-.004895,
.00129,-.00483,
.00044,-.00398,
315.*
4,1,15,-.00398,-.00044,
-.003999,-.000208,
-.004004,.000025,
-.003996,.000258,
-.00398,.00044,
-.00483,.00129,
-.004897,.001007,
-.004947,.000721,
-.004981,.000432,
-.004997,.000141,
-.004997,-.000149,
-.00498,-.00044,
-.004946,-.000729,
-.004895,-.001015,
-.00483,-.00129,
-.00398,-.00044,
315.*
4,1,15,-.00044,.00398,
-.000208,.003999,
.000025,.004004,
.000258,.003996,
.00044,.00398,
.00129,.00483,
.001007,.004897,
.000721,.004947,
.000432,.004981,
.000141,.004997,
-.000149,.004997,
-.00044,.00498,
-.000729,.004946,
-.001015,.004895,
-.00129,.00483,
-.00044,.00398,
315.*
%
%ADD24MACRO24*%
%AMMACRO13*
4,1,15,.00398,.00044,
.003999,.000208,
.004004,-.000025,
.003996,-.000258,
.00398,-.00044,
.00483,-.00129,
.004897,-.001007,
.004947,-.000721,
.004981,-.000432,
.004997,-.000141,
.004997,.000149,
.00498,.00044,
.004946,.000729,
.004895,.001015,
.00483,.00129,
.00398,.00044,
180.*
4,1,15,.00044,-.00398,
.000208,-.003999,
-.000025,-.004004,
-.000258,-.003996,
-.00044,-.00398,
-.00129,-.00483,
-.001007,-.004897,
-.000721,-.004947,
-.000432,-.004981,
-.000141,-.004997,
.000149,-.004997,
.00044,-.00498,
.000729,-.004946,
.001015,-.004895,
.00129,-.00483,
.00044,-.00398,
180.*
4,1,15,-.00398,-.00044,
-.003999,-.000208,
-.004004,.000025,
-.003996,.000258,
-.00398,.00044,
-.00483,.00129,
-.004897,.001007,
-.004947,.000721,
-.004981,.000432,
-.004997,.000141,
-.004997,-.000149,
-.00498,-.00044,
-.004946,-.000729,
-.004895,-.001015,
-.00483,-.00129,
-.00398,-.00044,
180.*
4,1,15,-.00044,.00398,
-.000208,.003999,
.000025,.004004,
.000258,.003996,
.00044,.00398,
.00129,.00483,
.001007,.004897,
.000721,.004947,
.000432,.004981,
.000141,.004997,
-.000149,.004997,
-.00044,.00498,
-.000729,.004946,
-.001015,.004895,
-.00129,.00483,
-.00044,.00398,
180.*
%
%ADD13MACRO13*%
%AMMACRO26*
4,1,15,-.00398,.00044,
-.003999,.000208,
-.004004,-.000025,
-.003996,-.000258,
-.00398,-.00044,
-.00483,-.00129,
-.004897,-.001007,
-.004947,-.000721,
-.004981,-.000432,
-.004997,-.000141,
-.004997,.000149,
-.00498,.00044,
-.004946,.000729,
-.004895,.001015,
-.00483,.00129,
-.00398,.00044,
270.*
4,1,15,-.00044,-.00398,
-.000208,-.003999,
.000025,-.004004,
.000258,-.003996,
.00044,-.00398,
.00129,-.00483,
.001007,-.004897,
.000721,-.004947,
.000432,-.004981,
.000141,-.004997,
-.000149,-.004997,
-.00044,-.00498,
-.000729,-.004946,
-.001015,-.004895,
-.00129,-.00483,
-.00044,-.00398,
270.*
4,1,15,.00398,-.00044,
.003999,-.000208,
.004004,.000025,
.003996,.000258,
.00398,.00044,
.00483,.00129,
.004897,.001007,
.004947,.000721,
.004981,.000432,
.004997,.000141,
.004997,-.000149,
.00498,-.00044,
.004946,-.000729,
.004895,-.001015,
.00483,-.00129,
.00398,-.00044,
270.*
4,1,15,.00044,.00398,
.000208,.003999,
-.000025,.004004,
-.000258,.003996,
-.00044,.00398,
-.00129,.00483,
-.001007,.004897,
-.000721,.004947,
-.000432,.004981,
-.000141,.004997,
.000149,.004997,
.00044,.00498,
.000729,.004946,
.001015,.004895,
.00129,.00483,
.00044,.00398,
270.*
%
%ADD26MACRO26*%
%AMMACRO15*
4,1,15,-.00398,.00044,
-.003999,.000208,
-.004004,-.000025,
-.003996,-.000258,
-.00398,-.00044,
-.00483,-.00129,
-.004897,-.001007,
-.004947,-.000721,
-.004981,-.000432,
-.004997,-.000141,
-.004997,.000149,
-.00498,.00044,
-.004946,.000729,
-.004895,.001015,
-.00483,.00129,
-.00398,.00044,
180.*
4,1,15,-.00044,-.00398,
-.000208,-.003999,
.000025,-.004004,
.000258,-.003996,
.00044,-.00398,
.00129,-.00483,
.001007,-.004897,
.000721,-.004947,
.000432,-.004981,
.000141,-.004997,
-.000149,-.004997,
-.00044,-.00498,
-.000729,-.004946,
-.001015,-.004895,
-.00129,-.00483,
-.00044,-.00398,
180.*
4,1,15,.00398,-.00044,
.003999,-.000208,
.004004,.000025,
.003996,.000258,
.00398,.00044,
.00483,.00129,
.004897,.001007,
.004947,.000721,
.004981,.000432,
.004997,.000141,
.004997,-.000149,
.00498,-.00044,
.004946,-.000729,
.004895,-.001015,
.00483,-.00129,
.00398,-.00044,
180.*
4,1,15,.00044,.00398,
.000208,.003999,
-.000025,.004004,
-.000258,.003996,
-.00044,.00398,
-.00129,.00483,
-.001007,.004897,
-.000721,.004947,
-.000432,.004981,
-.000141,.004997,
.000149,.004997,
.00044,.00498,
.000729,.004946,
.001015,.004895,
.00129,.00483,
.00044,.00398,
180.*
%
%ADD15MACRO15*%
%ADD29C,.02*%
%ADD30C,.006*%
%ADD34C,.09704*%
%ADD33C,.11004*%
%ADD31C,.11104*%
%ADD35C,.17004*%
%ADD32C,.39404*%
G75*
%LPD*%
G75*
G36*
G01X-6000Y-6000D02*
X1043402D01*
Y1998126D01*
X-6000D01*
Y-6000D01*
G37*
%LPC*%
G75*
G36*
G01X124665Y13315D02*
X119419Y3004D01*
X3937D01*
G02X3004Y3937I0J933D01*
G01Y596998D01*
X13760D01*
Y734169D01*
X17323D01*
G03Y748839I0J7335D01*
G01X13760D01*
Y924002D01*
X3004D01*
Y1092998D01*
X13760D01*
Y1230232D01*
X17323D01*
G03Y1244902I0J7335D01*
G01X13760D01*
Y1420002D01*
X3004D01*
Y1510498D01*
X13760D01*
Y1647555D01*
X17323D01*
G03Y1662224I0J7335D01*
G01X13760D01*
Y1838002D01*
X3004D01*
Y1988189D01*
G02X3937Y1989122I933J0D01*
G01X1033465D01*
G02X1034398Y1988189I0J-933D01*
G01Y1686599D01*
X1032220Y1684421D01*
X1028700D01*
G03X1020224Y1675945I0J-8476D01*
G01Y1621265D01*
X1018046Y1619087D01*
X993681D01*
G03Y1608866I0J-5110D01*
G01X1018046D01*
X1020224Y1606688D01*
Y1434291D01*
G03X1028700Y1425815I8477J1D01*
G01X1032220D01*
X1034398Y1423637D01*
Y3937D01*
G02X1033465Y3004I-933J0D01*
G01X148298D01*
X143084Y13251D01*
G02X142768Y14565I2585J1317D01*
G01Y17717D01*
G03X124949I-8909J0D01*
G01Y14565D01*
G02X124665Y13315I-2902J2D01*
G37*
%LPD*%
G75*
G36*
G01X1005938Y1903534D02*
Y1900889D01*
G03X1007242Y1897199I5875J1D01*
G02X988819I-9211J-7446D01*
G03X990122Y1900889I-4571J3689D01*
G01Y1903534D01*
G02X1005938I7908J0D01*
G37*
G36*
G01Y1082667D02*
Y1080022D01*
G03X1007242Y1076332I5875J1D01*
G02X988819I-9211J-7446D01*
G03X990122Y1080022I-4571J3689D01*
G01Y1082667D01*
G02X1005938I7908J0D01*
G37*
G36*
G01Y686998D02*
Y684353D01*
G03X1007242Y680663I5875J1D01*
G02X988819I-9211J-7446D01*
G03X990122Y684353I-4571J3689D01*
G01Y686998D01*
G02X1005938I7908J0D01*
G37*
G36*
G01Y163376D02*
Y160731D01*
G03X1007242Y157041I5875J1D01*
G02X988819I-9211J-7446D01*
G03X990122Y160731I-4571J3689D01*
G01Y163376D01*
G02X1005938I7908J0D01*
G37*
G36*
G01X920858Y1860549D02*
G02X916834I-2012J0D01*
G01Y1863750D01*
G02X920858Y1863749I2012J-1D01*
G01Y1860549D01*
G37*
G36*
G01Y1455037D02*
G02X916834I-2012J0D01*
G01Y1458238D01*
G02X920858Y1458237I2012J-1D01*
G01Y1455037D01*
G37*
G36*
G01Y1049525D02*
G02X916834I-2012J0D01*
G01Y1052726D01*
G02X920858Y1052725I2012J-1D01*
G01Y1049525D01*
G37*
G36*
G01Y644013D02*
G02X916834I-2012J0D01*
G01Y647214D01*
G02X920858Y647213I2012J-1D01*
G01Y644013D01*
G37*
G36*
G01Y238501D02*
G02X916834I-2012J0D01*
G01Y241702D01*
G02X920858Y241701I2012J-1D01*
G01Y238501D01*
G37*
G36*
G01X865430Y1909435D02*
G02X869452I2011J0D01*
G01Y1906234D01*
G02X865430Y1906235I-2011J1D01*
G01Y1909435D01*
G37*
G36*
G01Y1890538D02*
G02X869452I2011J0D01*
G01Y1887337D01*
G02X865430Y1887338I-2011J1D01*
G01Y1890538D01*
G37*
G36*
G01X870530Y1919484D02*
G02X875352I2411J0D01*
G01Y1915083D01*
G02X870530Y1915084I-2411J1D01*
G01Y1919484D01*
G37*
G36*
G01Y1900586D02*
G02X875352I2411J0D01*
G01Y1896185D01*
G02X870530Y1896186I-2411J1D01*
G01Y1900586D01*
G37*
G36*
G01X865430Y1928333D02*
G02X869452I2011J0D01*
G01Y1925132D01*
G02X865430Y1925133I-2011J1D01*
G01Y1928333D01*
G37*
G36*
G01X870530Y1938382D02*
G02X875352I2411J0D01*
G01Y1933981D01*
G02X870530Y1933982I-2411J1D01*
G01Y1938382D01*
G37*
G36*
G01X865430Y1840144D02*
G02X869452I2011J0D01*
G01Y1836943D01*
G02X865430Y1836944I-2011J1D01*
G01Y1840144D01*
G37*
G36*
G01X870530Y1850193D02*
G02X875352I2411J0D01*
G01Y1845792D01*
G02X870530Y1845793I-2411J1D01*
G01Y1850193D01*
G37*
G36*
G01X905146Y1855430D02*
G02Y1859454I0J2012D01*
G01X908347D01*
G02X908346Y1855430I-1J-2012D01*
G01X905146D01*
G37*
G36*
G01X865430Y1522821D02*
G02X869452I2011J0D01*
G01Y1519620D01*
G02X865430Y1519621I-2011J1D01*
G01Y1522821D01*
G37*
G36*
G01X870530Y1532870D02*
G02X875352I2411J0D01*
G01Y1528469D01*
G02X870530Y1528470I-2411J1D01*
G01Y1532870D01*
G37*
G36*
G01Y1513972D02*
G02X875352I2411J0D01*
G01Y1509571D01*
G02X870530Y1509572I-2411J1D01*
G01Y1513972D01*
G37*
G36*
G01X865430Y1485026D02*
G02X869452I2011J0D01*
G01Y1481825D01*
G02X865430Y1481826I-2011J1D01*
G01Y1485026D01*
G37*
G36*
G01X870530Y1444681D02*
G02X875352I2411J0D01*
G01Y1440280D01*
G02X870530Y1440281I-2411J1D01*
G01Y1444681D01*
G37*
G36*
G01X865430Y1503923D02*
G02X869452I2011J0D01*
G01Y1500722D01*
G02X865430Y1500723I-2011J1D01*
G01Y1503923D01*
G37*
G36*
G01X870530Y1495074D02*
G02X875352I2411J0D01*
G01Y1490673D01*
G02X870530Y1490674I-2411J1D01*
G01Y1495074D01*
G37*
G36*
G01X905146Y1449918D02*
G02Y1453942I0J2012D01*
G01X908347D01*
G02X908346Y1449918I-1J-2012D01*
G01X905146D01*
G37*
G36*
G01X865430Y1434632D02*
G02X869452I2011J0D01*
G01Y1431431D01*
G02X865430Y1431432I-2011J1D01*
G01Y1434632D01*
G37*
G36*
G01Y1098411D02*
G02X869452I2011J0D01*
G01Y1095210D01*
G02X865430Y1095211I-2011J1D01*
G01Y1098411D01*
G37*
G36*
G01Y1117309D02*
G02X869452I2011J0D01*
G01Y1114108D01*
G02X865430Y1114109I-2011J1D01*
G01Y1117309D01*
G37*
G36*
G01X870530Y1108460D02*
G02X875352I2411J0D01*
G01Y1104059D01*
G02X870530Y1104060I-2411J1D01*
G01Y1108460D01*
G37*
G36*
G01Y1089562D02*
G02X875352I2411J0D01*
G01Y1085161D01*
G02X870530Y1085162I-2411J1D01*
G01Y1089562D01*
G37*
G36*
G01X865430Y1079514D02*
G02X869452I2011J0D01*
G01Y1076313D01*
G02X865430Y1076314I-2011J1D01*
G01Y1079514D01*
G37*
G36*
G01X870530Y1127358D02*
G02X875352I2411J0D01*
G01Y1122957D01*
G02X870530Y1122958I-2411J1D01*
G01Y1127358D01*
G37*
G36*
G01X865430Y1029120D02*
G02X869452I2011J0D01*
G01Y1025919D01*
G02X865430Y1025920I-2011J1D01*
G01Y1029120D01*
G37*
G36*
G01X870530Y1039169D02*
G02X875352I2411J0D01*
G01Y1034768D01*
G02X870530Y1034769I-2411J1D01*
G01Y1039169D01*
G37*
G36*
G01X905146Y1044406D02*
G02Y1048430I0J2012D01*
G01X908347D01*
G02X908346Y1044406I-1J-2012D01*
G01X905146D01*
G37*
G36*
G01X865430Y711797D02*
G02X869452I2011J0D01*
G01Y708596D01*
G02X865430Y708597I-2011J1D01*
G01Y711797D01*
G37*
G36*
G01X870530Y721846D02*
G02X875352I2411J0D01*
G01Y717445D01*
G02X870530Y717446I-2411J1D01*
G01Y721846D01*
G37*
G36*
G01X865430Y674002D02*
G02X869452I2011J0D01*
G01Y670801D01*
G02X865430Y670802I-2011J1D01*
G01Y674002D01*
G37*
G36*
G01X870530Y684050D02*
G02X875352I2411J0D01*
G01Y679649D01*
G02X870530Y679650I-2411J1D01*
G01Y684050D01*
G37*
G36*
G01X865430Y692899D02*
G02X869452I2011J0D01*
G01Y689698D01*
G02X865430Y689699I-2011J1D01*
G01Y692899D01*
G37*
G36*
G01X870530Y702948D02*
G02X875352I2411J0D01*
G01Y698547D01*
G02X870530Y698548I-2411J1D01*
G01Y702948D01*
G37*
G36*
G01X905146Y638894D02*
G02Y642918I0J2012D01*
G01X908347D01*
G02X908346Y638894I-1J-2012D01*
G01X905146D01*
G37*
G36*
G01X865430Y623608D02*
G02X869452I2011J0D01*
G01Y620407D01*
G02X865430Y620408I-2011J1D01*
G01Y623608D01*
G37*
G36*
G01X870530Y633657D02*
G02X875352I2411J0D01*
G01Y629256D01*
G02X870530Y629257I-2411J1D01*
G01Y633657D01*
G37*
G36*
G01X865430Y287387D02*
G02X869452I2011J0D01*
G01Y284186D01*
G02X865430Y284187I-2011J1D01*
G01Y287387D01*
G37*
G36*
G01Y306285D02*
G02X869452I2011J0D01*
G01Y303084D01*
G02X865430Y303085I-2011J1D01*
G01Y306285D01*
G37*
G36*
G01X870530Y316334D02*
G02X875352I2411J0D01*
G01Y311933D01*
G02X870530Y311934I-2411J1D01*
G01Y316334D01*
G37*
G36*
G01Y297436D02*
G02X875352I2411J0D01*
G01Y293035D01*
G02X870530Y293036I-2411J1D01*
G01Y297436D01*
G37*
G36*
G01Y278538D02*
G02X875352I2411J0D01*
G01Y274137D01*
G02X870530Y274138I-2411J1D01*
G01Y278538D01*
G37*
G36*
G01X865430Y218096D02*
G02X869452I2011J0D01*
G01Y214895D01*
G02X865430Y214896I-2011J1D01*
G01Y218096D01*
G37*
G36*
G01X870530Y228145D02*
G02X875352I2411J0D01*
G01Y223744D01*
G02X870530Y223745I-2411J1D01*
G01Y228145D01*
G37*
G36*
G01X865430Y268490D02*
G02X869452I2011J0D01*
G01Y265289D01*
G02X865430Y265290I-2011J1D01*
G01Y268490D01*
G37*
G36*
G01X905146Y233382D02*
G02Y237406I0J2012D01*
G01X908347D01*
G02X908346Y233382I-1J-2012D01*
G01X905146D01*
G37*
G36*
G01X283498Y1903534D02*
Y1900889D01*
G03X284802Y1897199I5875J1D01*
G02X266379I-9211J-7446D01*
G03X267682Y1900889I-4571J3689D01*
G01Y1903534D01*
G02X283498I7908J0D01*
G37*
G36*
G01X295600Y1695412D02*
G02Y1691388I0J-2012D01*
G01X292399D01*
G02X292400Y1695412I1J2012D01*
G01X295600D01*
G37*
G36*
G01X282988Y1700600D02*
G02X287012I2012J0D01*
G01Y1697399D01*
G02X282988Y1697400I-2012J1D01*
G01Y1700600D01*
G37*
G36*
G01X283498Y1088573D02*
Y1085928D01*
G03X284802Y1082238I5875J1D01*
G02X266379I-9211J-7446D01*
G03X267682Y1085928I-4571J3689D01*
G01Y1088573D01*
G02X283498I7908J0D01*
G37*
G36*
G01Y685030D02*
Y682385D01*
G03X284802Y678695I5875J1D01*
G02X266379I-9211J-7446D01*
G03X267682Y682385I-4571J3689D01*
G01Y685030D01*
G02X283498I7908J0D01*
G37*
G36*
G01Y279528D02*
Y276883D01*
G03X284802Y273193I5875J1D01*
G02X266379I-9211J-7446D01*
G03X267682Y276883I-4571J3689D01*
G01Y279528D01*
G02X283498I7908J0D01*
G37*
G36*
G01X188488Y1863749D02*
G02X192512I2012J0D01*
G01Y1860548D01*
G02X188488Y1860549I-2012J1D01*
G01Y1863749D01*
G37*
G36*
G01Y1458237D02*
G02X192512I2012J0D01*
G01Y1455036D01*
G02X188488Y1455037I-2012J1D01*
G01Y1458237D01*
G37*
G36*
G01Y1052725D02*
G02X192512I2012J0D01*
G01Y1049524D01*
G02X188488Y1049525I-2012J1D01*
G01Y1052725D01*
G37*
G36*
G01Y647213D02*
G02X192512I2012J0D01*
G01Y644012D01*
G02X188488Y644013I-2012J1D01*
G01Y647213D01*
G37*
G36*
G01Y241701D02*
G02X192512I2012J0D01*
G01Y238500D01*
G02X188488Y238501I-2012J1D01*
G01Y241701D01*
G37*
G36*
G01X141106Y1925133D02*
G02X137084I-2011J0D01*
G01Y1928334D01*
G02X141106Y1928333I2011J-1D01*
G01Y1925133D01*
G37*
G36*
G01Y1906235D02*
G02X137084I-2011J0D01*
G01Y1909436D01*
G02X141106Y1909435I2011J-1D01*
G01Y1906235D01*
G37*
G36*
G01Y1887338D02*
G02X137084I-2011J0D01*
G01Y1890539D01*
G02X141106Y1890538I2011J-1D01*
G01Y1887338D01*
G37*
G36*
G01X147006Y1933982D02*
G02X142184I-2411J0D01*
G01Y1938383D01*
G02X147006Y1938382I2411J-1D01*
G01Y1933982D01*
G37*
G36*
G01X142184Y1919484D02*
G02X147006I2411J0D01*
G01Y1915083D01*
G02X142184Y1915084I-2411J1D01*
G01Y1919484D01*
G37*
G36*
G01X147006Y1896186D02*
G02X142184I-2411J0D01*
G01Y1900587D01*
G02X147006Y1900586I2411J-1D01*
G01Y1896186D01*
G37*
G36*
G01X176800Y1855430D02*
G02Y1859454I0J2012D01*
G01X180001D01*
G02X180000Y1855430I-1J-2012D01*
G01X176800D01*
G37*
G36*
G01X141106Y1836944D02*
G02X137084I-2011J0D01*
G01Y1840145D01*
G02X141106Y1840144I2011J-1D01*
G01Y1836944D01*
G37*
G36*
G01X147006Y1845793D02*
G02X142184I-2411J0D01*
G01Y1850194D01*
G02X147006Y1850193I2411J-1D01*
G01Y1845793D01*
G37*
G36*
G01X122988Y1753534D02*
G02X127012I2012J0D01*
G01Y1750333D01*
G02X122988Y1750334I-2012J1D01*
G01Y1753534D01*
G37*
G36*
G01X137084Y1522821D02*
G02X141106I2011J0D01*
G01Y1519620D01*
G02X137084Y1519621I-2011J1D01*
G01Y1522821D01*
G37*
G36*
G01X142184Y1513972D02*
G02X147006I2411J0D01*
G01Y1509571D01*
G02X142184Y1509572I-2411J1D01*
G01Y1513972D01*
G37*
G36*
G01Y1532870D02*
G02X147006I2411J0D01*
G01Y1528469D01*
G02X142184Y1528470I-2411J1D01*
G01Y1532870D01*
G37*
G36*
G01X180000Y1453942D02*
G02Y1449918I0J-2012D01*
G01X176799D01*
G02X176800Y1453942I1J2012D01*
G01X180000D01*
G37*
G36*
G01X137084Y1503923D02*
G02X141106I2011J0D01*
G01Y1500722D01*
G02X137084Y1500723I-2011J1D01*
G01Y1503923D01*
G37*
G36*
G01Y1485026D02*
G02X141106I2011J0D01*
G01Y1481825D01*
G02X137084Y1481826I-2011J1D01*
G01Y1485026D01*
G37*
G36*
G01X142184Y1495074D02*
G02X147006I2411J0D01*
G01Y1490673D01*
G02X142184Y1490674I-2411J1D01*
G01Y1495074D01*
G37*
G36*
G01Y1444681D02*
G02X147006I2411J0D01*
G01Y1440280D01*
G02X142184Y1440281I-2411J1D01*
G01Y1444681D01*
G37*
G36*
G01X137084Y1434632D02*
G02X141106I2011J0D01*
G01Y1431431D01*
G02X137084Y1431432I-2011J1D01*
G01Y1434632D01*
G37*
G36*
G01X127488Y1348021D02*
G02X131512I2012J0D01*
G01Y1344820D01*
G02X127488Y1344821I-2012J1D01*
G01Y1348021D01*
G37*
G36*
G01X137084Y1117309D02*
G02X141106I2011J0D01*
G01Y1114108D01*
G02X137084Y1114109I-2011J1D01*
G01Y1117309D01*
G37*
G36*
G01Y1098411D02*
G02X141106I2011J0D01*
G01Y1095210D01*
G02X137084Y1095211I-2011J1D01*
G01Y1098411D01*
G37*
G36*
G01Y1079514D02*
G02X141106I2011J0D01*
G01Y1076313D01*
G02X137084Y1076314I-2011J1D01*
G01Y1079514D01*
G37*
G36*
G01X142184Y1089562D02*
G02X147006I2411J0D01*
G01Y1085161D01*
G02X142184Y1085162I-2411J1D01*
G01Y1089562D01*
G37*
G36*
G01Y1108460D02*
G02X147006I2411J0D01*
G01Y1104059D01*
G02X142184Y1104060I-2411J1D01*
G01Y1108460D01*
G37*
G36*
G01Y1127358D02*
G02X147006I2411J0D01*
G01Y1122957D01*
G02X142184Y1122958I-2411J1D01*
G01Y1127358D01*
G37*
G36*
G01X180000Y1048430D02*
G02Y1044406I0J-2012D01*
G01X176799D01*
G02X176800Y1048430I1J2012D01*
G01X180000D01*
G37*
G36*
G01X137084Y1029120D02*
G02X141106I2011J0D01*
G01Y1025919D01*
G02X137084Y1025920I-2011J1D01*
G01Y1029120D01*
G37*
G36*
G01X142184Y1039169D02*
G02X147006I2411J0D01*
G01Y1034768D01*
G02X142184Y1034769I-2411J1D01*
G01Y1039169D01*
G37*
G36*
G01X164988Y942509D02*
G02X169012I2012J0D01*
G01Y939308D01*
G02X164988Y939309I-2012J1D01*
G01Y942509D01*
G37*
G36*
G01X137084Y711797D02*
G02X141106I2011J0D01*
G01Y708596D01*
G02X137084Y708597I-2011J1D01*
G01Y711797D01*
G37*
G36*
G01X142184Y721846D02*
G02X147006I2411J0D01*
G01Y717445D01*
G02X142184Y717446I-2411J1D01*
G01Y721846D01*
G37*
G36*
G01X180000Y642918D02*
G02Y638894I0J-2012D01*
G01X176799D01*
G02X176800Y642918I1J2012D01*
G01X180000D01*
G37*
G36*
G01X137084Y692899D02*
G02X141106I2011J0D01*
G01Y689698D01*
G02X137084Y689699I-2011J1D01*
G01Y692899D01*
G37*
G36*
G01Y674002D02*
G02X141106I2011J0D01*
G01Y670801D01*
G02X137084Y670802I-2011J1D01*
G01Y674002D01*
G37*
G36*
G01X142184Y702948D02*
G02X147006I2411J0D01*
G01Y698547D01*
G02X142184Y698548I-2411J1D01*
G01Y702948D01*
G37*
G36*
G01Y684050D02*
G02X147006I2411J0D01*
G01Y679649D01*
G02X142184Y679650I-2411J1D01*
G01Y684050D01*
G37*
G36*
G01X137084Y623608D02*
G02X141106I2011J0D01*
G01Y620407D01*
G02X137084Y620408I-2011J1D01*
G01Y623608D01*
G37*
G36*
G01X142184Y633657D02*
G02X147006I2411J0D01*
G01Y629256D01*
G02X142184Y629257I-2411J1D01*
G01Y633657D01*
G37*
G36*
G01X121988Y537073D02*
G02X126012I2012J0D01*
G01Y533872D01*
G02X121988Y533873I-2012J1D01*
G01Y537073D01*
G37*
G36*
G01X137084Y306285D02*
G02X141106I2011J0D01*
G01Y303084D01*
G02X137084Y303085I-2011J1D01*
G01Y306285D01*
G37*
G36*
G01Y287387D02*
G02X141106I2011J0D01*
G01Y284186D01*
G02X137084Y284187I-2011J1D01*
G01Y287387D01*
G37*
G36*
G01X142184Y278538D02*
G02X147006I2411J0D01*
G01Y274137D01*
G02X142184Y274138I-2411J1D01*
G01Y278538D01*
G37*
G36*
G01Y297436D02*
G02X147006I2411J0D01*
G01Y293035D01*
G02X142184Y293036I-2411J1D01*
G01Y297436D01*
G37*
G36*
G01Y316334D02*
G02X147006I2411J0D01*
G01Y311933D01*
G02X142184Y311934I-2411J1D01*
G01Y316334D01*
G37*
G36*
G01X180000Y237406D02*
G02Y233382I0J-2012D01*
G01X176799D01*
G02X176800Y237406I1J2012D01*
G01X180000D01*
G37*
G36*
G01X137084Y268490D02*
G02X141106I2011J0D01*
G01Y265289D01*
G02X137084Y265290I-2011J1D01*
G01Y268490D01*
G37*
G36*
G01Y218096D02*
G02X141106I2011J0D01*
G01Y214895D01*
G02X137084Y214896I-2011J1D01*
G01Y218096D01*
G37*
G36*
G01X142184Y228145D02*
G02X147006I2411J0D01*
G01Y223744D01*
G02X142184Y223745I-2411J1D01*
G01Y228145D01*
G37*
G36*
G01X121988Y131559D02*
G02X126012I2012J0D01*
G01Y128358D01*
G02X121988Y128359I-2012J1D01*
G01Y131559D01*
G37*
G36*
G01X97088Y1768381D02*
G02X101912I2412J0D01*
G01Y1763980D01*
G02X97088Y1763981I-2412J1D01*
G01Y1768381D01*
G37*
G36*
G01X102988Y1726836D02*
G02X107012I2012J0D01*
G01Y1723635D01*
G02X102988Y1723636I-2012J1D01*
G01Y1726836D01*
G37*
G36*
G01Y1777230D02*
G02X107012I2012J0D01*
G01Y1774029D01*
G02X102988Y1774030I-2012J1D01*
G01Y1777230D01*
G37*
G36*
G01X70012Y1750407D02*
G02X65988I-2012J0D01*
G01Y1753608D01*
G02X70012Y1753607I2012J-1D01*
G01Y1750407D01*
G37*
G36*
G01X97088Y1699090D02*
G02X101912I2412J0D01*
G01Y1694689D01*
G02X97088Y1694690I-2412J1D01*
G01Y1699090D01*
G37*
G36*
G01Y1680192D02*
G02X101912I2412J0D01*
G01Y1675791D01*
G02X97088Y1675792I-2412J1D01*
G01Y1680192D01*
G37*
G36*
G01X102988Y1707939D02*
G02X107012I2012J0D01*
G01Y1704738D01*
G02X102988Y1704739I-2012J1D01*
G01Y1707939D01*
G37*
G36*
G01Y1689041D02*
G02X107012I2012J0D01*
G01Y1685840D01*
G02X102988Y1685841I-2012J1D01*
G01Y1689041D01*
G37*
G36*
G01X97088Y1717988D02*
G02X101912I2412J0D01*
G01Y1713587D01*
G02X97088Y1713588I-2412J1D01*
G01Y1717988D01*
G37*
G36*
G01X107012Y1368518D02*
G02X102988I-2012J0D01*
G01Y1371719D01*
G02X107012Y1371718I2012J-1D01*
G01Y1368518D01*
G37*
G36*
G01X101912Y1289178D02*
G02X97088I-2412J0D01*
G01Y1293579D01*
G02X101912Y1293578I2412J-1D01*
G01Y1289178D01*
G37*
G36*
G01X97088Y1362869D02*
G02X101912I2412J0D01*
G01Y1358468D01*
G02X97088Y1358469I-2412J1D01*
G01Y1362869D01*
G37*
G36*
G01X101912Y1308076D02*
G02X97088I-2412J0D01*
G01Y1312477D01*
G02X101912Y1312476I2412J-1D01*
G01Y1308076D01*
G37*
G36*
G01X70012Y1344895D02*
G02X65988I-2012J0D01*
G01Y1348096D01*
G02X70012Y1348095I2012J-1D01*
G01Y1344895D01*
G37*
G36*
G01X107012Y1318124D02*
G02X102988I-2012J0D01*
G01Y1321325D01*
G02X107012Y1321324I2012J-1D01*
G01Y1318124D01*
G37*
G36*
G01Y1299227D02*
G02X102988I-2012J0D01*
G01Y1302428D01*
G02X107012Y1302427I2012J-1D01*
G01Y1299227D01*
G37*
G36*
G01X101912Y1270280D02*
G02X97088I-2412J0D01*
G01Y1274681D01*
G02X101912Y1274680I2412J-1D01*
G01Y1270280D01*
G37*
G36*
G01X107012Y1280329D02*
G02X102988I-2012J0D01*
G01Y1283530D01*
G02X107012Y1283529I2012J-1D01*
G01Y1280329D01*
G37*
G36*
G01X70012Y939383D02*
G02X65988I-2012J0D01*
G01Y942584D01*
G02X70012Y942583I2012J-1D01*
G01Y939383D01*
G37*
G36*
G01X107012Y963006D02*
G02X102988I-2012J0D01*
G01Y966207D01*
G02X107012Y966206I2012J-1D01*
G01Y963006D01*
G37*
G36*
G01X101912Y952957D02*
G02X97088I-2412J0D01*
G01Y957358D01*
G02X101912Y957357I2412J-1D01*
G01Y952957D01*
G37*
G36*
G01X97088Y869168D02*
G02X101912I2412J0D01*
G01Y864767D01*
G02X97088Y864768I-2412J1D01*
G01Y869168D01*
G37*
G36*
G01X107012Y912612D02*
G02X102988I-2012J0D01*
G01Y915813D01*
G02X107012Y915812I2012J-1D01*
G01Y912612D01*
G37*
G36*
G01Y893715D02*
G02X102988I-2012J0D01*
G01Y896916D01*
G02X107012Y896915I2012J-1D01*
G01Y893715D01*
G37*
G36*
G01Y874817D02*
G02X102988I-2012J0D01*
G01Y878018D01*
G02X107012Y878017I2012J-1D01*
G01Y874817D01*
G37*
G36*
G01X101912Y902564D02*
G02X97088I-2412J0D01*
G01Y906965D01*
G02X101912Y906964I2412J-1D01*
G01Y902564D01*
G37*
G36*
G01Y883666D02*
G02X97088I-2412J0D01*
G01Y888067D01*
G02X101912Y888066I2412J-1D01*
G01Y883666D01*
G37*
G36*
G01X97088Y551845D02*
G02X101912I2412J0D01*
G01Y547444D01*
G02X97088Y547445I-2412J1D01*
G01Y551845D01*
G37*
G36*
G01X70012Y533871D02*
G02X65988I-2012J0D01*
G01Y537072D01*
G02X70012Y537071I2012J-1D01*
G01Y533871D01*
G37*
G36*
G01X107012Y507100D02*
G02X102988I-2012J0D01*
G01Y510301D01*
G02X107012Y510300I2012J-1D01*
G01Y507100D01*
G37*
G36*
G01Y557494D02*
G02X102988I-2012J0D01*
G01Y560695D01*
G02X107012Y560694I2012J-1D01*
G01Y557494D01*
G37*
G36*
G01Y488203D02*
G02X102988I-2012J0D01*
G01Y491404D01*
G02X107012Y491403I2012J-1D01*
G01Y488203D01*
G37*
G36*
G01X101912Y497052D02*
G02X97088I-2412J0D01*
G01Y501453D01*
G02X101912Y501452I2412J-1D01*
G01Y497052D01*
G37*
G36*
G01X107012Y469305D02*
G02X102988I-2012J0D01*
G01Y472506D01*
G02X107012Y472505I2012J-1D01*
G01Y469305D01*
G37*
G36*
G01X97088Y463656D02*
G02X101912I2412J0D01*
G01Y459255D01*
G02X97088Y459256I-2412J1D01*
G01Y463656D01*
G37*
G36*
G01X101912Y478154D02*
G02X97088I-2412J0D01*
G01Y482555D01*
G02X101912Y482554I2412J-1D01*
G01Y478154D01*
G37*
G36*
G01X65988Y131559D02*
G02X70012I2012J0D01*
G01Y128358D01*
G02X65988Y128359I-2012J1D01*
G01Y131559D01*
G37*
G36*
G01X107012Y151982D02*
G02X102988I-2012J0D01*
G01Y155183D01*
G02X107012Y155182I2012J-1D01*
G01Y151982D01*
G37*
G36*
G01X101912Y141933D02*
G02X97088I-2412J0D01*
G01Y146334D01*
G02X101912Y146333I2412J-1D01*
G01Y141933D01*
G37*
G36*
G01Y72642D02*
G02X97088I-2412J0D01*
G01Y77043D01*
G02X101912Y77042I2412J-1D01*
G01Y72642D01*
G37*
G36*
G01X97088Y58244D02*
G02X101912I2412J0D01*
G01Y53843D01*
G02X97088Y53844I-2412J1D01*
G01Y58244D01*
G37*
G36*
G01X107012Y101588D02*
G02X102988I-2012J0D01*
G01Y104789D01*
G02X107012Y104788I2012J-1D01*
G01Y101588D01*
G37*
G36*
G01Y82691D02*
G02X102988I-2012J0D01*
G01Y85892D01*
G02X107012Y85891I2012J-1D01*
G01Y82691D01*
G37*
G36*
G01Y63793D02*
G02X102988I-2012J0D01*
G01Y66994D01*
G02X107012Y66993I2012J-1D01*
G01Y63793D01*
G37*
G36*
G01X101912Y91540D02*
G02X97088I-2412J0D01*
G01Y95941D01*
G02X101912Y95940I2412J-1D01*
G01Y91540D01*
G37*
G36*
G01X29562Y1922835D02*
Y1920190D01*
G03X30865Y1916500I5874J-1D01*
G02X12442I-9211J-7446D01*
G03X13746Y1920190I-4571J3691D01*
G01Y1922835D01*
G02X29562I7908J0D01*
G37*
G36*
G01X28700Y1771570D02*
G02Y1767546I0J-2012D01*
G01X25499D01*
G02X25500Y1771570I1J2012D01*
G01X28700D01*
G37*
G36*
G01X29540Y1732221D02*
G02X25518I-2011J0D01*
G01Y1735422D01*
G02X29540Y1735421I2011J-1D01*
G01Y1732221D01*
G37*
G36*
G01Y1744820D02*
G02X25518I-2011J0D01*
G01Y1748021D01*
G02X29540Y1748020I2011J-1D01*
G01Y1744820D01*
G37*
G36*
G01Y1757418D02*
G02X25518I-2011J0D01*
G01Y1760619D01*
G02X29540Y1760618I2011J-1D01*
G01Y1757418D01*
G37*
G36*
G01X22012Y1725729D02*
G02X17988I-2012J0D01*
G01Y1728930D01*
G02X22012Y1728929I2012J-1D01*
G01Y1725729D01*
G37*
G36*
G01Y1738328D02*
G02X17988I-2012J0D01*
G01Y1741529D01*
G02X22012Y1741528I2012J-1D01*
G01Y1738328D01*
G37*
G36*
G01Y1750926D02*
G02X17988I-2012J0D01*
G01Y1754127D01*
G02X22012Y1754126I2012J-1D01*
G01Y1750926D01*
G37*
G36*
G01X25518Y1688177D02*
G02X29540I2011J0D01*
G01Y1684976D01*
G02X25518Y1684977I-2011J1D01*
G01Y1688177D01*
G37*
G36*
G01Y1700776D02*
G02X29540I2011J0D01*
G01Y1697575D01*
G02X25518Y1697576I-2011J1D01*
G01Y1700776D01*
G37*
G36*
G01Y1675579D02*
G02X29540I2011J0D01*
G01Y1672378D01*
G02X25518Y1672379I-2011J1D01*
G01Y1675579D01*
G37*
G36*
G01X29540Y1719623D02*
G02X25518I-2011J0D01*
G01Y1722824D01*
G02X29540Y1722823I2011J-1D01*
G01Y1719623D01*
G37*
G36*
G01X17988Y1669087D02*
G02X22012I2012J0D01*
G01Y1665886D01*
G02X17988Y1665887I-2012J1D01*
G01Y1669087D01*
G37*
G36*
G01Y1681685D02*
G02X22012I2012J0D01*
G01Y1678484D01*
G02X17988Y1678485I-2012J1D01*
G01Y1681685D01*
G37*
G36*
G01Y1694283D02*
G02X22012I2012J0D01*
G01Y1691082D01*
G02X17988Y1691083I-2012J1D01*
G01Y1694283D01*
G37*
G36*
G01X22012Y1713131D02*
G02X17988I-2012J0D01*
G01Y1716332D01*
G02X22012Y1716331I2012J-1D01*
G01Y1713131D01*
G37*
G36*
G01X29540Y1583999D02*
G02X25518I-2011J0D01*
G01Y1587200D01*
G02X29540Y1587199I2011J-1D01*
G01Y1583999D01*
G37*
G36*
G01Y1596597D02*
G02X25518I-2011J0D01*
G01Y1599798D01*
G02X29540Y1599797I2011J-1D01*
G01Y1596597D01*
G37*
G36*
G01Y1609196D02*
G02X25518I-2011J0D01*
G01Y1612397D01*
G02X29540Y1612396I2011J-1D01*
G01Y1609196D01*
G37*
G36*
G01Y1621794D02*
G02X25518I-2011J0D01*
G01Y1624995D01*
G02X29540Y1624994I2011J-1D01*
G01Y1621794D01*
G37*
G36*
G01X25518Y1637593D02*
G02X29540I2011J0D01*
G01Y1634392D01*
G02X25518Y1634393I-2011J1D01*
G01Y1637593D01*
G37*
G36*
G01X22012Y1590296D02*
G02X17988I-2012J0D01*
G01Y1593497D01*
G02X22012Y1593496I2012J-1D01*
G01Y1590296D01*
G37*
G36*
G01Y1602894D02*
G02X17988I-2012J0D01*
G01Y1606095D01*
G02X22012Y1606094I2012J-1D01*
G01Y1602894D01*
G37*
G36*
G01Y1615493D02*
G02X17988I-2012J0D01*
G01Y1618694D01*
G02X22012Y1618693I2012J-1D01*
G01Y1615493D01*
G37*
G36*
G01Y1628091D02*
G02X17988I-2012J0D01*
G01Y1631292D01*
G02X22012Y1631291I2012J-1D01*
G01Y1628091D01*
G37*
G36*
G01X17988Y1643890D02*
G02X22012I2012J0D01*
G01Y1640689D01*
G02X17988Y1640690I-2012J1D01*
G01Y1643890D01*
G37*
G36*
G01X33001Y1516112D02*
G02Y1520134I0J2011D01*
G01X36202D01*
G02X36201Y1516112I-1J-2011D01*
G01X33001D01*
G37*
G36*
G01X25518Y1527356D02*
G02X29540I2011J0D01*
G01Y1524155D01*
G02X25518Y1524156I-2011J1D01*
G01Y1527356D01*
G37*
G36*
G01Y1539955D02*
G02X29540I2011J0D01*
G01Y1536754D01*
G02X25518Y1536755I-2011J1D01*
G01Y1539955D01*
G37*
G36*
G01Y1552553D02*
G02X29540I2011J0D01*
G01Y1549352D01*
G02X25518Y1549353I-2011J1D01*
G01Y1552553D01*
G37*
G36*
G01Y1565152D02*
G02X29540I2011J0D01*
G01Y1561951D01*
G02X25518Y1561952I-2011J1D01*
G01Y1565152D01*
G37*
G36*
G01X17988Y1533654D02*
G02X22012I2012J0D01*
G01Y1530453D01*
G02X17988Y1530454I-2012J1D01*
G01Y1533654D01*
G37*
G36*
G01Y1546252D02*
G02X22012I2012J0D01*
G01Y1543051D01*
G02X17988Y1543052I-2012J1D01*
G01Y1546252D01*
G37*
G36*
G01Y1558850D02*
G02X22012I2012J0D01*
G01Y1555649D01*
G02X17988Y1555650I-2012J1D01*
G01Y1558850D01*
G37*
G36*
G01Y1571449D02*
G02X22012I2012J0D01*
G01Y1568248D01*
G02X17988Y1568249I-2012J1D01*
G01Y1571449D01*
G37*
G36*
G01X29540Y1365102D02*
G02X25518I-2011J0D01*
G01Y1368303D01*
G02X29540Y1368302I2011J-1D01*
G01Y1365102D01*
G37*
G36*
G01Y1377700D02*
G02X25518I-2011J0D01*
G01Y1380901D01*
G02X29540Y1380900I2011J-1D01*
G01Y1377700D01*
G37*
G36*
G01X25518Y1393499D02*
G02X29540I2011J0D01*
G01Y1390298D01*
G02X25518Y1390299I-2011J1D01*
G01Y1393499D01*
G37*
G36*
G01X29540Y1402897D02*
G02X25518I-2011J0D01*
G01Y1406098D01*
G02X29540Y1406097I2011J-1D01*
G01Y1402897D01*
G37*
G36*
G01X17988Y1374599D02*
G02X22012I2012J0D01*
G01Y1371398D01*
G02X17988Y1371399I-2012J1D01*
G01Y1374599D01*
G37*
G36*
G01Y1387198D02*
G02X22012I2012J0D01*
G01Y1383997D01*
G02X17988Y1383998I-2012J1D01*
G01Y1387198D01*
G37*
G36*
G01Y1399796D02*
G02X22012I2012J0D01*
G01Y1396595D01*
G02X17988Y1396596I-2012J1D01*
G01Y1399796D01*
G37*
G36*
G01Y1412395D02*
G02X22012I2012J0D01*
G01Y1409194D01*
G02X17988Y1409195I-2012J1D01*
G01Y1412395D01*
G37*
G36*
G01X29540Y1292661D02*
G02X25518I-2011J0D01*
G01Y1295862D01*
G02X29540Y1295861I2011J-1D01*
G01Y1292661D01*
G37*
G36*
G01X25518Y1318108D02*
G02X29540I2011J0D01*
G01Y1314907D01*
G02X25518Y1314908I-2011J1D01*
G01Y1318108D01*
G37*
G36*
G01Y1330707D02*
G02X29540I2011J0D01*
G01Y1327506D01*
G02X25518Y1327507I-2011J1D01*
G01Y1330707D01*
G37*
G36*
G01Y1343305D02*
G02X29540I2011J0D01*
G01Y1340104D01*
G02X25518Y1340105I-2011J1D01*
G01Y1343305D01*
G37*
G36*
G01Y1355904D02*
G02X29540I2011J0D01*
G01Y1352703D01*
G02X25518Y1352704I-2011J1D01*
G01Y1355904D01*
G37*
G36*
G01X17988Y1362001D02*
G02X22012I2012J0D01*
G01Y1358800D01*
G02X17988Y1358801I-2012J1D01*
G01Y1362001D01*
G37*
G36*
G01Y1349402D02*
G02X22012I2012J0D01*
G01Y1346201D01*
G02X17988Y1346202I-2012J1D01*
G01Y1349402D01*
G37*
G36*
G01Y1336804D02*
G02X22012I2012J0D01*
G01Y1333603D01*
G02X17988Y1333604I-2012J1D01*
G01Y1336804D01*
G37*
G36*
G01Y1324206D02*
G02X22012I2012J0D01*
G01Y1321005D01*
G02X17988Y1321006I-2012J1D01*
G01Y1324206D01*
G37*
G36*
G01Y1302158D02*
G02X22012I2012J0D01*
G01Y1298957D01*
G02X17988Y1298958I-2012J1D01*
G01Y1302158D01*
G37*
G36*
G01Y1289560D02*
G02X22012I2012J0D01*
G01Y1286359D01*
G02X17988Y1286360I-2012J1D01*
G01Y1289560D01*
G37*
G36*
G01X29540Y1280063D02*
G02X25518I-2011J0D01*
G01Y1283264D01*
G02X29540Y1283263I2011J-1D01*
G01Y1280063D01*
G37*
G36*
G01Y1267464D02*
G02X25518I-2011J0D01*
G01Y1270665D01*
G02X29540Y1270664I2011J-1D01*
G01Y1267464D01*
G37*
G36*
G01Y1254866D02*
G02X25518I-2011J0D01*
G01Y1258067D01*
G02X29540Y1258066I2011J-1D01*
G01Y1254866D01*
G37*
G36*
G01Y1223370D02*
G02X25518I-2011J0D01*
G01Y1226571D01*
G02X29540Y1226570I2011J-1D01*
G01Y1223370D01*
G37*
G36*
G01X17988Y1276961D02*
G02X22012I2012J0D01*
G01Y1273760D01*
G02X17988Y1273761I-2012J1D01*
G01Y1276961D01*
G37*
G36*
G01Y1264363D02*
G02X22012I2012J0D01*
G01Y1261162D01*
G02X17988Y1261163I-2012J1D01*
G01Y1264363D01*
G37*
G36*
G01Y1251765D02*
G02X22012I2012J0D01*
G01Y1248564D01*
G02X17988Y1248565I-2012J1D01*
G01Y1251765D01*
G37*
G36*
G01Y1220269D02*
G02X22012I2012J0D01*
G01Y1217068D01*
G02X17988Y1217069I-2012J1D01*
G01Y1220269D01*
G37*
G36*
G01X29540Y1210771D02*
G02X25518I-2011J0D01*
G01Y1213972D01*
G02X29540Y1213971I2011J-1D01*
G01Y1210771D01*
G37*
G36*
G01Y1198173D02*
G02X25518I-2011J0D01*
G01Y1201374D01*
G02X29540Y1201373I2011J-1D01*
G01Y1198173D01*
G37*
G36*
G01Y1185574D02*
G02X25518I-2011J0D01*
G01Y1188775D01*
G02X29540Y1188774I2011J-1D01*
G01Y1185574D01*
G37*
G36*
G01Y1172976D02*
G02X25518I-2011J0D01*
G01Y1176177D01*
G02X29540Y1176176I2011J-1D01*
G01Y1172976D01*
G37*
G36*
G01Y1160378D02*
G02X25518I-2011J0D01*
G01Y1163579D01*
G02X29540Y1163578I2011J-1D01*
G01Y1160378D01*
G37*
G36*
G01Y1147779D02*
G02X25518I-2011J0D01*
G01Y1150980D01*
G02X29540Y1150979I2011J-1D01*
G01Y1147779D01*
G37*
G36*
G01X17988Y1195072D02*
G02X22012I2012J0D01*
G01Y1191871D01*
G02X17988Y1191872I-2012J1D01*
G01Y1195072D01*
G37*
G36*
G01Y1207670D02*
G02X22012I2012J0D01*
G01Y1204469D01*
G02X17988Y1204470I-2012J1D01*
G01Y1207670D01*
G37*
G36*
G01Y1182473D02*
G02X22012I2012J0D01*
G01Y1179272D01*
G02X17988Y1179273I-2012J1D01*
G01Y1182473D01*
G37*
G36*
G01Y1169875D02*
G02X22012I2012J0D01*
G01Y1166674D01*
G02X17988Y1166675I-2012J1D01*
G01Y1169875D01*
G37*
G36*
G01Y1157276D02*
G02X22012I2012J0D01*
G01Y1154075D01*
G02X17988Y1154076I-2012J1D01*
G01Y1157276D01*
G37*
G36*
G01Y1144678D02*
G02X22012I2012J0D01*
G01Y1141477D01*
G02X17988Y1141478I-2012J1D01*
G01Y1144678D01*
G37*
G36*
G01X25518Y1113384D02*
G02X29540I2011J0D01*
G01Y1110183D01*
G02X25518Y1110184I-2011J1D01*
G01Y1113384D01*
G37*
G36*
G01Y1138381D02*
G02X29540I2011J0D01*
G01Y1135180D01*
G02X25518Y1135181I-2011J1D01*
G01Y1138381D01*
G37*
G36*
G01Y1100785D02*
G02X29540I2011J0D01*
G01Y1097584D01*
G02X25518Y1097585I-2011J1D01*
G01Y1100785D01*
G37*
G36*
G01X17988Y1119481D02*
G02X22012I2012J0D01*
G01Y1116280D01*
G02X17988Y1116281I-2012J1D01*
G01Y1119481D01*
G37*
G36*
G01Y1106883D02*
G02X22012I2012J0D01*
G01Y1103682D01*
G02X17988Y1103683I-2012J1D01*
G01Y1106883D01*
G37*
G36*
G01X25518Y859441D02*
G02X29540I2011J0D01*
G01Y856240D01*
G02X25518Y856241I-2011J1D01*
G01Y859441D01*
G37*
G36*
G01X29540Y868839D02*
G02X25518I-2011J0D01*
G01Y872040D01*
G02X29540Y872039I2011J-1D01*
G01Y868839D01*
G37*
G36*
G01X25518Y884687D02*
G02X29540I2011J0D01*
G01Y881486D01*
G02X25518Y881487I-2011J1D01*
G01Y884687D01*
G37*
G36*
G01Y910034D02*
G02X29540I2011J0D01*
G01Y906833D01*
G02X25518Y906834I-2011J1D01*
G01Y910034D01*
G37*
G36*
G01Y897436D02*
G02X29540I2011J0D01*
G01Y894235D01*
G02X25518Y894236I-2011J1D01*
G01Y897436D01*
G37*
G36*
G01X17988Y853339D02*
G02X22012I2012J0D01*
G01Y850138D01*
G02X17988Y850139I-2012J1D01*
G01Y853339D01*
G37*
G36*
G01Y865938D02*
G02X22012I2012J0D01*
G01Y862737D01*
G02X17988Y862738I-2012J1D01*
G01Y865938D01*
G37*
G36*
G01Y878536D02*
G02X22012I2012J0D01*
G01Y875335D01*
G02X17988Y875336I-2012J1D01*
G01Y878536D01*
G37*
G36*
G01Y903733D02*
G02X22012I2012J0D01*
G01Y900532D01*
G02X17988Y900533I-2012J1D01*
G01Y903733D01*
G37*
G36*
G01Y916332D02*
G02X22012I2012J0D01*
G01Y913131D01*
G02X17988Y913132I-2012J1D01*
G01Y916332D01*
G37*
G36*
G01X25518Y846842D02*
G02X29540I2011J0D01*
G01Y843641D01*
G02X25518Y843642I-2011J1D01*
G01Y846842D01*
G37*
G36*
G01Y834444D02*
G02X29540I2011J0D01*
G01Y831243D01*
G02X25518Y831244I-2011J1D01*
G01Y834444D01*
G37*
G36*
G01Y821845D02*
G02X29540I2011J0D01*
G01Y818644D01*
G02X25518Y818645I-2011J1D01*
G01Y821845D01*
G37*
G36*
G01Y809247D02*
G02X29540I2011J0D01*
G01Y806046D01*
G02X25518Y806047I-2011J1D01*
G01Y809247D01*
G37*
G36*
G01Y796648D02*
G02X29540I2011J0D01*
G01Y793447D01*
G02X25518Y793448I-2011J1D01*
G01Y796648D01*
G37*
G36*
G01X17988Y790347D02*
G02X22012I2012J0D01*
G01Y787146D01*
G02X17988Y787147I-2012J1D01*
G01Y790347D01*
G37*
G36*
G01Y802946D02*
G02X22012I2012J0D01*
G01Y799745D01*
G02X17988Y799746I-2012J1D01*
G01Y802946D01*
G37*
G36*
G01Y815544D02*
G02X22012I2012J0D01*
G01Y812343D01*
G02X17988Y812344I-2012J1D01*
G01Y815544D01*
G37*
G36*
G01Y828143D02*
G02X22012I2012J0D01*
G01Y824942D01*
G02X17988Y824943I-2012J1D01*
G01Y828143D01*
G37*
G36*
G01Y840741D02*
G02X22012I2012J0D01*
G01Y837540D01*
G02X17988Y837541I-2012J1D01*
G01Y840741D01*
G37*
G36*
G01X25518Y774601D02*
G02X29540I2011J0D01*
G01Y771400D01*
G02X25518Y771401I-2011J1D01*
G01Y774601D01*
G37*
G36*
G01Y762003D02*
G02X29540I2011J0D01*
G01Y758802D01*
G02X25518Y758803I-2011J1D01*
G01Y762003D01*
G37*
G36*
G01Y730507D02*
G02X29540I2011J0D01*
G01Y727306D01*
G02X25518Y727307I-2011J1D01*
G01Y730507D01*
G37*
G36*
G01Y717908D02*
G02X29540I2011J0D01*
G01Y714707D01*
G02X25518Y714708I-2011J1D01*
G01Y717908D01*
G37*
G36*
G01X17988Y768300D02*
G02X22012I2012J0D01*
G01Y765099D01*
G02X17988Y765100I-2012J1D01*
G01Y768300D01*
G37*
G36*
G01Y755702D02*
G02X22012I2012J0D01*
G01Y752501D01*
G02X17988Y752502I-2012J1D01*
G01Y755702D01*
G37*
G36*
G01Y724206D02*
G02X22012I2012J0D01*
G01Y721005D01*
G02X17988Y721006I-2012J1D01*
G01Y724206D01*
G37*
G36*
G01Y711607D02*
G02X22012I2012J0D01*
G01Y708406D01*
G02X17988Y708407I-2012J1D01*
G01Y711607D01*
G37*
G36*
G01Y636017D02*
G02X22012I2012J0D01*
G01Y632816D01*
G02X17988Y632817I-2012J1D01*
G01Y636017D01*
G37*
G36*
G01Y699009D02*
G02X22012I2012J0D01*
G01Y695808D01*
G02X17988Y695809I-2012J1D01*
G01Y699009D01*
G37*
G36*
G01X25518Y642518D02*
G02X29540I2011J0D01*
G01Y639317D01*
G02X25518Y639318I-2011J1D01*
G01Y642518D01*
G37*
G36*
G01Y667715D02*
G02X29540I2011J0D01*
G01Y664514D01*
G02X25518Y664515I-2011J1D01*
G01Y667715D01*
G37*
G36*
G01Y680313D02*
G02X29540I2011J0D01*
G01Y677112D01*
G02X25518Y677113I-2011J1D01*
G01Y680313D01*
G37*
G36*
G01Y692911D02*
G02X29540I2011J0D01*
G01Y689710D01*
G02X25518Y689711I-2011J1D01*
G01Y692911D01*
G37*
G36*
G01Y705510D02*
G02X29540I2011J0D01*
G01Y702309D01*
G02X25518Y702310I-2011J1D01*
G01Y705510D01*
G37*
G36*
G01X17988Y686410D02*
G02X22012I2012J0D01*
G01Y683209D01*
G02X17988Y683210I-2012J1D01*
G01Y686410D01*
G37*
G36*
G01Y673812D02*
G02X22012I2012J0D01*
G01Y670611D01*
G02X17988Y670612I-2012J1D01*
G01Y673812D01*
G37*
G36*
G01Y661213D02*
G02X22012I2012J0D01*
G01Y658012D01*
G02X17988Y658013I-2012J1D01*
G01Y661213D01*
G37*
G36*
G01Y648615D02*
G02X22012I2012J0D01*
G01Y645414D01*
G02X17988Y645415I-2012J1D01*
G01Y648615D01*
G37*
G36*
G01X25518Y617271D02*
G02X29540I2011J0D01*
G01Y614070D01*
G02X25518Y614071I-2011J1D01*
G01Y617271D01*
G37*
G36*
G01Y604722D02*
G02X29540I2011J0D01*
G01Y601521D01*
G02X25518Y601522I-2011J1D01*
G01Y604722D01*
G37*
G36*
G01Y629919D02*
G02X29540I2011J0D01*
G01Y626718D01*
G02X25518Y626719I-2011J1D01*
G01Y629919D01*
G37*
G36*
G01X17988Y623418D02*
G02X22012I2012J0D01*
G01Y620217D01*
G02X17988Y620218I-2012J1D01*
G01Y623418D01*
G37*
G36*
G01Y610820D02*
G02X22012I2012J0D01*
G01Y607619D01*
G02X17988Y607620I-2012J1D01*
G01Y610820D01*
G37*
G36*
G01X41372Y281496D02*
Y278851D01*
G03X42676Y275161I5875J1D01*
G02X24253I-9212J-7446D01*
G03X25556Y278851I-4571J3689D01*
G01Y281496D01*
G02X41372I7908J0D01*
G37*
G54D34*
X82087Y28858D03*
Y178464D03*
Y434370D03*
Y583976D03*
Y839882D03*
Y989488D03*
Y1245394D03*
Y1395000D03*
Y1650906D03*
Y1800512D03*
X162008Y191614D03*
Y341220D03*
Y597126D03*
Y746732D03*
Y1002638D03*
Y1152244D03*
Y1408150D03*
Y1557756D03*
Y1813662D03*
Y1963268D03*
X890354Y191614D03*
Y341220D03*
Y597126D03*
Y746732D03*
Y1002638D03*
Y1152244D03*
Y1408150D03*
Y1557756D03*
Y1813662D03*
Y1963268D03*
G54D33*
X25499Y1950499D03*
X1010999Y43999D03*
X1010499Y1950499D03*
G54D31*
X11811Y571426D03*
Y949378D03*
Y1067489D03*
Y1484811D03*
Y1445441D03*
Y1862763D03*
G54D35*
X1023228Y1416024D03*
Y1694212D03*
G54D32*
X33469Y1029523D03*
X269690Y1490152D03*
G54D22*
X72835Y17047D03*
Y190275D03*
Y422559D03*
Y595787D03*
Y828071D03*
Y1001299D03*
Y1233583D03*
Y1406811D03*
Y1639095D03*
Y1812323D03*
X171260Y179803D03*
Y353031D03*
Y585315D03*
Y758543D03*
Y990827D03*
Y1164055D03*
Y1396339D03*
Y1569567D03*
Y1801851D03*
Y1975079D03*
X899606Y179803D03*
Y353031D03*
Y585315D03*
Y758543D03*
Y990827D03*
Y1164055D03*
Y1396339D03*
Y1569567D03*
Y1801851D03*
Y1975079D03*
G54D16*
X20000Y607620D03*
Y610820D03*
Y620218D03*
Y623418D03*
X27529Y601522D03*
Y604722D03*
Y614071D03*
Y617271D03*
Y626719D03*
Y629919D03*
X20000Y658013D03*
Y661213D03*
Y670612D03*
Y673812D03*
Y683210D03*
Y686410D03*
Y632817D03*
Y636017D03*
Y695809D03*
Y699009D03*
Y645415D03*
Y648615D03*
X27529Y664515D03*
Y667715D03*
Y677113D03*
Y680313D03*
Y689711D03*
Y692911D03*
Y702310D03*
Y639318D03*
Y642518D03*
X20000Y708407D03*
Y711607D03*
Y721006D03*
Y724206D03*
Y752502D03*
Y755702D03*
Y765100D03*
Y768300D03*
X27529Y714708D03*
Y717908D03*
Y727307D03*
Y730507D03*
Y758803D03*
Y762003D03*
Y705510D03*
Y771401D03*
Y774601D03*
X27699Y737535D03*
X20000Y837541D03*
Y840741D03*
Y787147D03*
Y790347D03*
Y799746D03*
Y802946D03*
Y812344D03*
Y815544D03*
Y824943D03*
Y828143D03*
X27529Y843642D03*
Y846842D03*
Y793448D03*
Y796648D03*
Y806047D03*
Y809247D03*
Y818645D03*
Y821845D03*
Y831244D03*
Y834444D03*
X20000Y900533D03*
Y903733D03*
Y850139D03*
Y853339D03*
Y913132D03*
Y916332D03*
Y862738D03*
Y865938D03*
Y875336D03*
Y878536D03*
X27529Y894236D03*
Y897436D03*
Y856241D03*
Y859441D03*
Y906834D03*
Y910034D03*
Y868839D03*
Y872039D03*
Y881487D03*
Y884687D03*
X34872Y890906D03*
X30000Y991000D03*
X23291Y1062791D03*
X20000Y1103683D03*
Y1106883D03*
Y1116281D03*
Y1119481D03*
X27529Y1135181D03*
Y1138381D03*
Y1097585D03*
Y1100785D03*
Y1110184D03*
Y1113384D03*
X32335Y1122002D03*
X37396Y1130912D03*
X33971Y1131741D03*
X20000Y1141478D03*
Y1144678D03*
Y1191872D03*
Y1195072D03*
Y1154076D03*
Y1157276D03*
Y1204470D03*
Y1207670D03*
Y1166675D03*
Y1169875D03*
Y1179273D03*
Y1182473D03*
X27529Y1185574D03*
Y1188774D03*
Y1147779D03*
Y1150979D03*
Y1198173D03*
Y1201373D03*
Y1160378D03*
Y1163578D03*
Y1210771D03*
Y1172976D03*
Y1176176D03*
X20000Y1261163D03*
Y1264363D03*
Y1273761D03*
Y1276961D03*
Y1217069D03*
Y1220269D03*
Y1248565D03*
Y1251765D03*
X27529Y1254866D03*
Y1258066D03*
Y1267464D03*
Y1270664D03*
Y1280063D03*
Y1283263D03*
Y1213971D03*
Y1223370D03*
Y1226570D03*
X33201Y1230674D03*
X32959Y1234478D03*
X36000Y1236000D03*
X20000Y1321006D03*
Y1324206D03*
Y1333604D03*
Y1336804D03*
Y1346202D03*
Y1349402D03*
Y1286360D03*
Y1289560D03*
Y1298958D03*
Y1302158D03*
X27529Y1314908D03*
Y1318108D03*
Y1327507D03*
Y1330707D03*
Y1340105D03*
Y1343305D03*
Y1352704D03*
Y1355904D03*
Y1292661D03*
Y1295861D03*
X36170Y1308434D03*
X33699Y1301782D03*
X26500Y1305121D03*
X33938Y1311000D03*
X38500D03*
X30000Y1305000D03*
X30700Y1308600D03*
X20000Y1371399D03*
Y1374599D03*
Y1383998D03*
Y1387198D03*
Y1396596D03*
Y1399796D03*
Y1358801D03*
Y1362001D03*
Y1409195D03*
Y1412395D03*
X27529Y1365102D03*
Y1368302D03*
Y1377700D03*
Y1380900D03*
Y1390299D03*
Y1393499D03*
Y1402897D03*
Y1406097D03*
X27000Y1417500D03*
X32500Y1417600D03*
X28000Y1444000D03*
X20000Y1530454D03*
Y1533654D03*
Y1543052D03*
Y1546252D03*
Y1555650D03*
Y1558850D03*
Y1568249D03*
Y1571449D03*
X27529Y1524156D03*
Y1527356D03*
Y1536755D03*
Y1539955D03*
Y1549353D03*
Y1552553D03*
Y1561952D03*
Y1565152D03*
X33001Y1518123D03*
X36201D03*
X20000Y1640690D03*
Y1643890D03*
Y1593496D03*
Y1590296D03*
Y1606094D03*
Y1602894D03*
Y1618693D03*
Y1615493D03*
Y1631291D03*
Y1628091D03*
X27529Y1634393D03*
Y1637593D03*
Y1587199D03*
Y1583999D03*
Y1599797D03*
Y1596597D03*
Y1612396D03*
Y1609196D03*
Y1624994D03*
Y1621794D03*
X20000Y1716331D03*
Y1713131D03*
Y1665887D03*
Y1669087D03*
Y1678485D03*
Y1681685D03*
Y1691083D03*
Y1694283D03*
X27529Y1719623D03*
Y1672379D03*
Y1675579D03*
Y1684977D03*
Y1688177D03*
Y1697576D03*
Y1700776D03*
X35900Y1706000D03*
X34224Y1709000D03*
X38000Y1715000D03*
X20000Y1728929D03*
Y1725729D03*
Y1741528D03*
Y1738328D03*
Y1754126D03*
Y1750926D03*
X27529Y1722823D03*
Y1735421D03*
Y1732221D03*
Y1748020D03*
Y1744820D03*
Y1760618D03*
Y1757418D03*
X25500Y1769558D03*
X28700D03*
X30200Y1970300D03*
X96000Y119000D03*
X99500Y95940D03*
Y91540D03*
Y77042D03*
Y72642D03*
Y58244D03*
Y53844D03*
X105000Y104788D03*
Y101588D03*
Y85891D03*
Y82691D03*
Y66993D03*
Y63793D03*
X72500Y61161D03*
X71000Y125236D03*
X68000Y128359D03*
Y131559D03*
X99500Y146333D03*
Y141933D03*
X105000Y155182D03*
Y151982D03*
X99300Y201000D03*
X60306Y212338D03*
X80153Y230246D03*
X85427Y239715D03*
X100400Y208300D03*
X70500Y242988D03*
X80300Y234465D03*
X97400Y220200D03*
X66610Y295956D03*
X56024Y292549D03*
X110000Y362500D03*
X106500D03*
X110000Y366000D03*
X106500D03*
X92700Y358400D03*
X52066Y370649D03*
X99500Y482554D03*
Y478154D03*
Y463656D03*
Y459256D03*
X105000Y472505D03*
Y469305D03*
X72500Y466673D03*
X71000Y530748D03*
X96000Y524000D03*
X68000Y533871D03*
Y537071D03*
X99500Y551845D03*
Y547445D03*
Y501452D03*
Y497052D03*
X105000Y557494D03*
Y510300D03*
Y507100D03*
Y491403D03*
Y488203D03*
X71000Y524464D03*
X89400Y603250D03*
X95900Y605500D03*
X62426Y607740D03*
X105000Y560694D03*
X88600Y623300D03*
X80153Y635758D03*
X85223Y645227D03*
X70500Y648500D03*
X48000Y649500D03*
X46500Y653500D03*
X80300Y639977D03*
X50560Y653500D03*
X106500Y771500D03*
X110000D03*
Y768000D03*
X106500D03*
X86900Y774750D03*
X49500Y771000D03*
X80215Y777137D03*
X47500Y901500D03*
X99500Y906964D03*
Y902564D03*
Y888066D03*
Y883666D03*
Y869168D03*
Y864768D03*
X105000Y915812D03*
Y912612D03*
Y896915D03*
Y893715D03*
Y878017D03*
Y874817D03*
X72500Y872185D03*
X96000Y930000D03*
X71000Y936260D03*
X68000Y939383D03*
Y942583D03*
X99500Y957357D03*
Y952957D03*
X105000Y966206D03*
Y963006D03*
X65500Y927500D03*
X71000Y925500D03*
X93000Y1005700D03*
X81689Y1039600D03*
X77750Y1056750D03*
X96500Y1011200D03*
X64037Y1016654D03*
X74000Y1047500D03*
X41000Y1057500D03*
X81689Y1049400D03*
X106100Y1030000D03*
X42286Y1089500D03*
Y1085500D03*
X67090Y1070360D03*
X41608Y1125065D03*
X39959Y1128308D03*
X110000Y1173500D03*
X106500D03*
X110000Y1177000D03*
X106500D03*
X88500Y1177300D03*
X40097Y1142513D03*
X85300Y1182000D03*
X99500Y1274680D03*
Y1270280D03*
X105000Y1283529D03*
Y1280329D03*
X72500Y1277697D03*
X71000Y1341772D03*
X96000Y1335000D03*
X68000Y1344895D03*
Y1348095D03*
X99500Y1312476D03*
Y1308076D03*
Y1293578D03*
Y1289178D03*
X105000Y1321324D03*
Y1318124D03*
Y1302427D03*
Y1299227D03*
X71000Y1335488D03*
X58900Y1317000D03*
X96250Y1414400D03*
X62962Y1422600D03*
X100000Y1423000D03*
X99900Y1419600D03*
X99500Y1362869D03*
Y1358469D03*
X105000Y1371718D03*
Y1368518D03*
X110000Y1470000D03*
X99300Y1431200D03*
X82748Y1455148D03*
X76750Y1462762D03*
X80153Y1446781D03*
X73000Y1455100D03*
X69365Y1474719D03*
X80300Y1451000D03*
X82005Y1540500D03*
X85808D03*
X110500Y1573200D03*
X107000D03*
X103500D03*
X80465Y1570120D03*
X109050Y1540600D03*
X46893Y1519979D03*
X47368Y1527323D03*
X42644Y1521957D03*
X46845Y1514264D03*
X43000Y1526000D03*
X42960Y1517408D03*
X107000Y1576700D03*
X103500D03*
X110500D03*
X42919Y1583175D03*
X64525Y1591016D03*
X99500Y1713588D03*
Y1717988D03*
Y1694690D03*
Y1699090D03*
Y1675792D03*
Y1680192D03*
X105000Y1704739D03*
Y1707939D03*
Y1685841D03*
Y1689041D03*
X72500Y1683209D03*
X51635Y1665355D03*
X66400Y1706900D03*
X71000Y1747284D03*
X104000Y1747800D03*
X68000Y1750407D03*
Y1753607D03*
X99500Y1763981D03*
Y1768381D03*
X105000Y1774030D03*
Y1777230D03*
Y1723636D03*
Y1726836D03*
X67000Y1738000D03*
X71015D03*
X100300Y1820800D03*
X77159Y1818277D03*
X91036Y1835282D03*
X72123Y1841183D03*
X100287Y1825915D03*
X100300Y1830000D03*
X80600Y1848900D03*
X98000Y1848800D03*
X85000Y1817100D03*
X74100Y1796200D03*
X67800Y1855200D03*
X93625Y1802200D03*
X52000Y1877500D03*
X112366Y1883985D03*
X46868Y1887765D03*
X60897Y1885848D03*
X48000Y1877500D03*
X80400Y1957900D03*
X73400D03*
X76900D03*
X87500Y1954300D03*
X80400Y1954400D03*
X83900D03*
X73400D03*
X76900D03*
X57800Y1961800D03*
X177300Y39000D03*
X180800D03*
X184300D03*
X180800Y35500D03*
X177300D03*
X184300D03*
X152400Y41500D03*
X184461Y103368D03*
X125700Y54400D03*
X150557Y142854D03*
X167298Y147703D03*
X159500Y181000D03*
X124000Y128359D03*
Y131559D03*
X167298Y151203D03*
X114579Y137775D03*
X154875Y160500D03*
X173095Y244842D03*
X148000Y241500D03*
X180000Y235394D03*
X176800D03*
X144595Y223745D03*
Y228145D03*
X139095Y214896D03*
Y218096D03*
Y265290D03*
X172900Y249400D03*
X143600Y252100D03*
X129000Y255500D03*
X114295Y338300D03*
X144595Y274138D03*
Y278538D03*
Y293036D03*
Y297436D03*
Y311934D03*
Y316334D03*
X139095Y268490D03*
Y284187D03*
Y287387D03*
Y303085D03*
Y306285D03*
X171595Y308917D03*
X134000Y409500D03*
X137500D03*
X130500D03*
X127000D03*
X117000Y362500D03*
Y366000D03*
X113500Y362500D03*
Y366000D03*
X173800Y379800D03*
X157200Y412000D03*
X158500Y408000D03*
X127000Y413000D03*
X130500D03*
X134000D03*
X137500D03*
X170500Y478500D03*
X125300Y438000D03*
X157750Y541250D03*
X184500Y553500D03*
X124000Y533873D03*
Y537073D03*
X157750Y544750D03*
X159600Y581400D03*
X155500Y574000D03*
X144595Y629257D03*
X139095Y620408D03*
Y623608D03*
X150850Y574350D03*
X148000Y648000D03*
X173095Y650354D03*
X180000Y640906D03*
X176800D03*
X144595Y633657D03*
Y679650D03*
Y684050D03*
Y698548D03*
Y702948D03*
X139095Y670802D03*
Y674002D03*
Y689699D03*
Y692899D03*
X173000Y655200D03*
X117000Y771500D03*
Y768000D03*
X113500Y771500D03*
Y768000D03*
X117945Y743800D03*
X144595Y717446D03*
Y721846D03*
X139095Y708597D03*
Y711797D03*
X171595Y714429D03*
X127000Y818500D03*
X130500D03*
X134000D03*
X137500D03*
X134000Y815000D03*
X137500D03*
X130500D03*
X127000D03*
X156800Y816000D03*
X126800Y842500D03*
X143800Y807400D03*
X178000Y960000D03*
X162200Y988000D03*
X161095Y980622D03*
X167000Y939309D03*
Y942509D03*
X174500Y960000D03*
X157200Y950800D03*
X155900Y954200D03*
X157000Y957500D03*
X161200Y946100D03*
X161700Y950800D03*
X173095Y1055866D03*
X148000Y1053500D03*
X180000Y1046418D03*
X176800D03*
X144595Y1034769D03*
Y1039169D03*
X139095Y1025920D03*
Y1029120D03*
X137500Y1014500D03*
X173000Y1060400D03*
X139300Y1067000D03*
X144595Y1085162D03*
Y1089562D03*
Y1104060D03*
Y1108460D03*
Y1122958D03*
Y1127358D03*
X139095Y1076314D03*
Y1079514D03*
Y1095211D03*
Y1098411D03*
Y1114109D03*
Y1117309D03*
X171595Y1119941D03*
X117000Y1173500D03*
Y1177000D03*
X113500Y1173500D03*
Y1177000D03*
X117900Y1149200D03*
X127000Y1224000D03*
X130500Y1220500D03*
Y1224000D03*
X134000D03*
X137500D03*
X134000Y1220500D03*
X137500D03*
X127000D03*
X158052Y1216052D03*
X129150Y1252050D03*
X147956Y1347802D03*
X129500Y1344821D03*
Y1348021D03*
X154709Y1344513D03*
X140125Y1381300D03*
X167301Y1363238D03*
Y1366838D03*
X158875Y1376100D03*
X118000Y1470000D03*
X148000Y1458000D03*
X126000Y1466000D03*
X173095Y1461378D03*
X180000Y1451930D03*
X176800D03*
X144595Y1440281D03*
Y1444681D03*
Y1490674D03*
Y1495074D03*
X139095Y1431432D03*
Y1434632D03*
Y1481826D03*
Y1485026D03*
Y1500723D03*
X148095Y1468752D03*
X173100Y1466300D03*
X114000Y1573200D03*
X128250Y1506500D03*
X144595Y1509572D03*
Y1513972D03*
Y1528470D03*
Y1532870D03*
X139095Y1503923D03*
Y1519621D03*
Y1522821D03*
X171595Y1525453D03*
X126800Y1630100D03*
X130300D03*
X133800D03*
X126800Y1626600D03*
X130300D03*
X137300Y1630100D03*
Y1626600D03*
X133800D03*
X114000Y1576700D03*
X150200Y1628000D03*
X126900Y1654700D03*
X144400Y1720400D03*
X177717Y1778162D03*
X180075Y1790692D03*
X125000Y1750334D03*
Y1753534D03*
X136500Y1733000D03*
X137000Y1727500D03*
X140825Y1729825D03*
X157898Y1780145D03*
X140300Y1724100D03*
X147200Y1724400D03*
X173095Y1866890D03*
X148000Y1864000D03*
X180000Y1857442D03*
X176800D03*
X144595Y1850193D03*
Y1845793D03*
X139095Y1840144D03*
Y1836944D03*
X151452Y1810000D03*
X144595Y1900586D03*
Y1896186D03*
Y1919484D03*
Y1915084D03*
Y1938382D03*
Y1933982D03*
X139095Y1890538D03*
Y1887338D03*
Y1909435D03*
Y1906235D03*
Y1928333D03*
Y1925133D03*
X171595Y1930965D03*
X113500Y1875970D03*
X173500Y1871700D03*
X137300Y1969900D03*
X136800Y1959900D03*
X150800Y1958900D03*
X150600Y1970300D03*
X187800Y39000D03*
Y35500D03*
X208150Y32250D03*
X220500Y67500D03*
X198800Y158000D03*
Y162500D03*
Y167000D03*
X190500Y238501D03*
Y241701D03*
X188854Y527099D03*
Y530902D03*
X206500Y538750D03*
Y546250D03*
Y531250D03*
X195250Y561300D03*
Y576700D03*
X200250Y572100D03*
X190500Y644013D03*
Y647213D03*
X214700Y784200D03*
X190330Y913530D03*
X198900Y969500D03*
X207350Y968627D03*
X198900Y974000D03*
Y978500D03*
X229500Y946600D03*
X198900Y965477D03*
X208875Y957200D03*
X190500Y1049525D03*
Y1052725D03*
X196000Y1070300D03*
X193400Y1373000D03*
Y1377500D03*
Y1382000D03*
X214500Y1459000D03*
X190500Y1455037D03*
Y1458237D03*
X248500Y1713005D03*
Y1716808D03*
X197900Y1781500D03*
X251900Y1769900D03*
X203299Y1763350D03*
X197900Y1786000D03*
Y1790500D03*
X222500Y1776200D03*
X255495Y1738573D03*
X251692D03*
X203299Y1759750D03*
X224875Y1768100D03*
X190500Y1860549D03*
Y1863749D03*
X292600Y166955D03*
X318656Y391440D03*
X326156D03*
X293000Y385000D03*
X294500Y408000D03*
X315000Y412000D03*
X321400Y404400D03*
X327500Y377000D03*
X321500Y408500D03*
X312500Y393050D03*
X303200Y422600D03*
X313200Y427500D03*
X317000D03*
X321500Y425200D03*
Y417000D03*
Y421000D03*
X296470Y555500D03*
X292667D03*
X297300Y505017D03*
X273500Y597000D03*
Y589000D03*
Y585000D03*
Y577000D03*
X284000Y612000D03*
X273500Y573000D03*
Y565000D03*
X296000Y612000D03*
X292000D03*
X316000D03*
X308000D03*
X304000D03*
X290580Y559000D03*
X298450D03*
X320100Y587200D03*
X317500Y559000D03*
X286130Y615700D03*
X270000Y579030D03*
X310030Y615500D03*
X298030Y621000D03*
X269800Y590930D03*
X270000Y567130D03*
X289933Y615700D03*
X270000Y582833D03*
X313833Y615500D03*
X301833Y621000D03*
X269800Y594733D03*
X270000Y570933D03*
X293500Y738000D03*
X326167Y811099D03*
Y814902D03*
X292000Y837000D03*
X321500Y847000D03*
X315000Y842000D03*
X321500Y838500D03*
X321400Y834400D03*
X327500Y807000D03*
X312000Y824500D03*
X295200Y903000D03*
X305200D03*
Y913000D03*
X295200D03*
X303500Y853100D03*
X321500Y855200D03*
Y851000D03*
X317000Y857900D03*
X313200D03*
X292500Y965500D03*
X294000Y1111500D03*
X321400Y1205900D03*
X321500Y1210000D03*
X327500Y1178500D03*
X312500Y1194000D03*
X295000Y1245000D03*
X294500Y1254000D03*
X302500Y1224000D03*
X321600Y1226600D03*
X313200Y1228800D03*
X317000D03*
X314437Y1213382D03*
X321500Y1222500D03*
Y1218500D03*
X287167Y1380000D03*
X290970D03*
X319500Y1389000D03*
X301400Y1401500D03*
X315500Y1389000D03*
X293100Y1383500D03*
X284900D03*
X273500Y1419500D03*
Y1411500D03*
Y1423500D03*
X326500Y1417500D03*
Y1425700D03*
Y1405400D03*
Y1413500D03*
Y1429700D03*
X328000Y1381500D03*
Y1374000D03*
X327500Y1368500D03*
X273500Y1403500D03*
X307500Y1389000D03*
X330000Y1423470D03*
X270100Y1425697D03*
X330300Y1411100D03*
X270000Y1413530D03*
X330000Y1419667D03*
X270100Y1429500D03*
X330300Y1407297D03*
X270000Y1417333D03*
X273500Y1431500D03*
X287600Y1448000D03*
X279650D03*
X299600D03*
X291600D03*
X326500Y1437700D03*
X311600Y1448000D03*
X303600D03*
X330000Y1435170D03*
X293830Y1451500D03*
X305830Y1451300D03*
X282030Y1451400D03*
X330000Y1431367D03*
X297633Y1451500D03*
X309633Y1451300D03*
X285833Y1451400D03*
X318156Y1692440D03*
X325656D03*
X301800Y1722100D03*
X265500Y1722000D03*
X283500D03*
X285000Y1700600D03*
X295600Y1693400D03*
X285000Y1697400D03*
X292400Y1693400D03*
X315000Y1712000D03*
X321500Y1721000D03*
X327500Y1677000D03*
X321500Y1717000D03*
Y1708500D03*
X321400Y1704400D03*
X313500Y1692500D03*
X276402Y1726146D03*
X272599D03*
X297000Y1777000D03*
Y1752000D03*
X302000D03*
X321500Y1725200D03*
X317000Y1727300D03*
X313200D03*
X363750Y54250D03*
X382200Y81500D03*
X382000Y98000D03*
X358000Y64000D03*
X344500Y71750D03*
X360750Y124000D03*
X369000Y294000D03*
X401500Y410250D03*
X356257Y344176D03*
X391750Y344500D03*
X383750D03*
X348256Y344114D03*
X331500Y389000D03*
X365100Y371200D03*
X397000Y380250D03*
X375200Y371250D03*
X349870Y348870D03*
X331300Y408500D03*
X351729Y455810D03*
X379258Y455892D03*
X387249Y455882D03*
X343729Y455810D03*
X364758Y429249D03*
X375200Y429250D03*
X350137Y451250D03*
X385607Y451232D03*
X339500Y572667D03*
Y576470D03*
X332500Y605000D03*
X336000Y570580D03*
Y578600D03*
X332500Y593000D03*
Y601000D03*
X377250Y774500D03*
X385238Y774122D03*
X331500Y819000D03*
X358800Y803600D03*
X368700Y803750D03*
X388250Y803300D03*
X385196Y779112D03*
X331300Y838500D03*
X402000Y844000D03*
X360100Y808080D03*
X351792Y885835D03*
X379270Y885897D03*
X387292D03*
X343770D03*
X360800Y858500D03*
X375200Y858250D03*
X343894Y880707D03*
X379372Y880728D03*
X391758Y1145676D03*
X383757Y1145655D03*
X331500Y1190500D03*
X364300Y1174900D03*
X374200Y1174750D03*
X391900Y1150250D03*
X331300Y1210000D03*
X398750Y1188250D03*
X359175Y1179640D03*
X351750Y1257380D03*
X379270D03*
X387292Y1257360D03*
X343760Y1257381D03*
X365200Y1229800D03*
X400700Y1237500D03*
X375200Y1229750D03*
X343822Y1252222D03*
X379395Y1252274D03*
X356247Y1644123D03*
X348257Y1644132D03*
X356174Y1649291D03*
X331500Y1691000D03*
X369100Y1673700D03*
X385250Y1673000D03*
X331500Y1708500D03*
X395500Y1690500D03*
X376890Y1678000D03*
X376808Y1755434D03*
X373005D03*
X379000Y1736000D03*
X351750Y1755500D03*
X343750D03*
X383000Y1736300D03*
X365700Y1727700D03*
X383000Y1728700D03*
X375700Y1727750D03*
X343668Y1750741D03*
X379000Y1726000D03*
X405500Y277500D03*
X405000Y289000D03*
X410550Y420500D03*
X425890Y820729D03*
X425891Y812750D03*
X404000Y840500D03*
X420722Y820627D03*
X410550Y850500D03*
X405500Y1192000D03*
X408300Y1237500D03*
X425500Y1215250D03*
Y1223250D03*
X420763Y1223185D03*
X425879Y1721724D03*
X425500Y1713750D03*
X420732Y1721757D03*
X547659Y1560537D03*
X542159D03*
Y1566037D03*
X547659D03*
X663000Y535500D03*
X661500Y650500D03*
X662000Y826600D03*
X665000Y937000D03*
X660000Y1053500D03*
X662000Y1183500D03*
X657000Y1331500D03*
X662000Y1459000D03*
X634200Y1561200D03*
Y1565700D03*
X639700Y1561200D03*
Y1565700D03*
X646200Y1561200D03*
Y1565700D03*
X651700Y1561200D03*
Y1565700D03*
X753500Y1662000D03*
Y1666500D03*
X759000Y1662000D03*
Y1666500D03*
X765500Y1662000D03*
Y1666500D03*
X728700Y1933100D03*
X755995Y1968282D03*
X792343Y193599D03*
X832500Y171000D03*
X824500D03*
X816500D03*
X792343Y197402D03*
X836500Y362500D03*
X833000D03*
X840000Y366000D03*
Y362500D03*
X833000Y366000D03*
X836500D03*
X813350Y369250D03*
X782500Y648000D03*
X840000Y771500D03*
X833000D03*
X836500D03*
X840000Y768000D03*
X836500D03*
X833000D03*
X836500Y1177000D03*
X833000D03*
X840000D03*
Y1582500D03*
X833000D03*
X836500D03*
X840000Y1579000D03*
X836500D03*
X833000D03*
X813000Y1585750D03*
X808500Y1621500D03*
X814000D03*
Y1626000D03*
X808500D03*
X814000Y1630500D03*
X808500D03*
X771000Y1662000D03*
Y1666500D03*
X815000Y1785000D03*
X834750Y1823285D03*
X819000Y1839000D03*
X796339Y1937007D03*
Y1940507D03*
X804239Y1953307D03*
Y1956807D03*
X800739D03*
Y1953307D03*
X797239D03*
Y1956807D03*
X785239Y1960907D03*
X885531Y164804D03*
X896441Y147203D03*
X844000Y190000D03*
X866961Y162539D03*
X896547Y150803D03*
X890469Y164804D03*
X864975Y148875D03*
X876500Y251000D03*
X901441Y244842D03*
X908346Y235394D03*
X905146D03*
X872941Y223745D03*
Y228145D03*
X867441Y214896D03*
Y218096D03*
Y265290D03*
X901600Y249800D03*
X844050Y337300D03*
X872941Y274138D03*
Y278538D03*
Y293036D03*
Y297436D03*
Y311934D03*
Y316334D03*
X867441Y268490D03*
Y284187D03*
Y287387D03*
Y303085D03*
Y306285D03*
X899941Y308917D03*
X843500Y366000D03*
Y362500D03*
X895547Y552715D03*
X857735Y553465D03*
X895547Y556315D03*
X865125Y544000D03*
X883781Y564519D03*
X872941Y629257D03*
X867441Y620408D03*
Y623608D03*
X888719Y564519D03*
X876500Y648000D03*
X901441Y650354D03*
X908346Y640906D03*
X905146D03*
X872941Y633657D03*
Y679650D03*
Y684050D03*
Y698548D03*
Y702948D03*
X867441Y670802D03*
Y674002D03*
Y689699D03*
Y692899D03*
X901200Y655100D03*
X843500Y771500D03*
Y768000D03*
X846200Y743300D03*
X872941Y717446D03*
Y721846D03*
X867441Y708597D03*
Y711797D03*
X899941Y714429D03*
X883781Y970031D03*
X895547Y958227D03*
X857623Y958977D03*
X895547Y961827D03*
X888719Y970031D03*
X865125Y949600D03*
X901441Y1055866D03*
X876500Y1053500D03*
X908346Y1046418D03*
X905146D03*
X872941Y1034769D03*
Y1039169D03*
X867441Y1025920D03*
Y1029120D03*
X901300Y1060700D03*
X872941Y1085162D03*
Y1089562D03*
Y1104060D03*
Y1108460D03*
Y1122958D03*
Y1127358D03*
X867441Y1076314D03*
Y1079514D03*
Y1095211D03*
Y1098411D03*
Y1114109D03*
Y1117309D03*
X899941Y1119941D03*
X843500Y1177000D03*
X844600Y1148700D03*
X865125Y1346488D03*
X883219Y1373504D03*
X895647Y1363738D03*
X857688Y1364488D03*
X895647Y1367338D03*
X887438Y1373374D03*
X901441Y1461378D03*
X876500Y1459000D03*
X908346Y1451930D03*
X905146D03*
X872941Y1440281D03*
Y1444681D03*
Y1490674D03*
Y1495074D03*
X867441Y1431432D03*
Y1434632D03*
Y1481826D03*
Y1485026D03*
Y1500723D03*
X901400Y1466100D03*
X845600Y1554300D03*
X872941Y1509572D03*
Y1513972D03*
Y1528470D03*
Y1532870D03*
X867441Y1503923D03*
Y1519621D03*
Y1522821D03*
X899941Y1525453D03*
X843500Y1582500D03*
Y1579000D03*
X901500Y1681500D03*
X881353Y1650749D03*
X877853D03*
Y1654249D03*
X881353D03*
X896500Y1681000D03*
X859500Y1696000D03*
X898500Y1734000D03*
X910500Y1734600D03*
X895547Y1769250D03*
X883781Y1781054D03*
X895547Y1772850D03*
X888719Y1781054D03*
X865125Y1751800D03*
X902500Y1734000D03*
X910500Y1724700D03*
X876000Y1864000D03*
X901441Y1866890D03*
X908346Y1857442D03*
X905146D03*
X872941Y1845793D03*
Y1850193D03*
X867441Y1836944D03*
Y1840144D03*
X872941Y1896186D03*
Y1900586D03*
Y1915084D03*
Y1919484D03*
Y1933982D03*
Y1938382D03*
X867441Y1887338D03*
Y1890538D03*
Y1906235D03*
Y1909435D03*
Y1925133D03*
Y1928333D03*
X899941Y1930965D03*
X901200Y1871600D03*
X879500Y1970000D03*
X880000Y1955500D03*
X862000Y1969900D03*
Y1960500D03*
X844700Y1945200D03*
X926347Y155500D03*
Y160000D03*
Y164453D03*
X918846Y238501D03*
Y241701D03*
X926365Y561000D03*
Y569965D03*
Y565500D03*
X918846Y644013D03*
Y647213D03*
X926477Y966500D03*
Y971000D03*
Y975477D03*
X918846Y1049525D03*
Y1052725D03*
X926300Y1372000D03*
Y1380988D03*
Y1376500D03*
X918846Y1455037D03*
Y1458237D03*
X959000Y1631000D03*
X943500Y1646989D03*
X973000Y1641500D03*
X931000Y1659000D03*
X959000Y1657000D03*
Y1675000D03*
X926500Y1660000D03*
X941000Y1653000D03*
X934825Y1682285D03*
X947000Y1654500D03*
X915250Y1687500D03*
X919250Y1711500D03*
X926400Y1777500D03*
Y1782000D03*
Y1786500D03*
X921900Y1722400D03*
X918846Y1860549D03*
Y1863749D03*
G54D17*
X25000Y988000D03*
X27825Y995000D03*
X78675Y380704D03*
X47500Y660500D03*
X45000Y1057000D03*
X77607Y1565391D03*
X183344Y808200D03*
X126221Y861250D03*
Y853750D03*
X163170Y1210999D03*
X117387Y1536250D03*
Y1543750D03*
X122844Y1672400D03*
X130344D03*
X213244Y23725D03*
X243156Y382060D03*
X235656D03*
X228156Y438500D03*
X220656D03*
X206700Y575000D03*
X190844Y808200D03*
X242700Y1266656D03*
Y1259156D03*
X232344Y1740000D03*
X239844D03*
X284000Y541344D03*
Y548844D03*
X317156Y1193440D03*
X324656D03*
X276344Y1183060D03*
X268844D03*
X401500Y395500D03*
X393500Y422000D03*
X401500Y830000D03*
X393500Y852000D03*
X402000Y1196500D03*
X396637Y1176000D03*
X358156Y1411000D03*
X350656D03*
X402000Y1695000D03*
X379500Y1673750D03*
X427500Y297156D03*
Y304656D03*
X412500Y1130750D03*
Y1138250D03*
X438656Y1669000D03*
X431156D03*
X458156Y1743000D03*
X450656D03*
X512656Y623500D03*
X520156D03*
X555000Y524344D03*
Y531844D03*
X807756Y377775D03*
X808256Y783275D03*
X807756Y1188775D03*
Y1594275D03*
X979500Y1669750D03*
Y1662250D03*
G54D21*
X7600Y1855000D03*
X17500Y1827500D03*
X22600Y1825200D03*
X17500Y1832500D03*
X22500Y1830000D03*
X17500Y1837500D03*
X22500Y1835000D03*
X17500Y1842500D03*
X22500Y1840000D03*
X17500Y1847500D03*
X22500Y1845000D03*
X17500Y1852500D03*
X22500Y1850000D03*
X17500Y1857500D03*
X22500Y1855000D03*
Y1865000D03*
X17500Y1867500D03*
X22500Y1860000D03*
X12500Y1845000D03*
Y1850000D03*
Y1855000D03*
Y1840000D03*
X17500Y1872500D03*
X22500Y1870000D03*
X12500D03*
X71200Y36900D03*
X136100Y41200D03*
X935000Y1425000D03*
X984900Y1430400D03*
X953800Y1424900D03*
X945000Y1425000D03*
X935000Y1455000D03*
Y1475000D03*
Y1445000D03*
Y1465000D03*
Y1435000D03*
X945000Y1475000D03*
X955000D03*
X965000D03*
X945000Y1465000D03*
X955000D03*
X965000D03*
X945000Y1455000D03*
X955000D03*
X965000D03*
X945000Y1445000D03*
X955000D03*
X965000D03*
X945000Y1435000D03*
X955000D03*
X965000D03*
Y1495000D03*
X955000D03*
X935000Y1485000D03*
Y1495000D03*
X945000D03*
Y1485000D03*
X955000D03*
X965000D03*
X975000Y1495000D03*
Y1485000D03*
Y1475000D03*
Y1465000D03*
Y1455000D03*
Y1445000D03*
Y1435000D03*
X935000Y1505000D03*
X955000D03*
X945000D03*
X965000D03*
X990600Y1427100D03*
X995000Y1425000D03*
X1005000D03*
G54D19*
X36401Y1521623D03*
X32801D03*
X83248Y1059636D03*
X82748Y1465560D03*
X105700Y1548200D03*
X121600Y54700D03*
X148700Y413400D03*
X148600Y818700D03*
X157325Y1223850D03*
X123200Y1947250D03*
X205625Y38750D03*
X288000Y586484D03*
X313000Y559000D03*
X329600Y583200D03*
X332500Y597000D03*
Y589000D03*
X829388Y1695500D03*
X825388D03*
X833388D03*
X837388D03*
X825388Y1739500D03*
X829388D03*
X833388D03*
X837388D03*
X841388Y1695500D03*
X873962Y1672000D03*
Y1676500D03*
Y1681500D03*
Y1685500D03*
X906000Y1713500D03*
X891000Y1720000D03*
X916500Y1729500D03*
G54D11*
X20000Y40000D03*
Y20000D03*
X5500Y40982D03*
Y20982D03*
X10018Y5500D03*
X30018D03*
X20000Y80000D03*
Y100000D03*
Y120000D03*
Y60000D03*
X5500Y120982D03*
Y100982D03*
Y80982D03*
Y60982D03*
X20000Y160000D03*
Y180000D03*
Y140000D03*
X5500Y180982D03*
Y160982D03*
Y140982D03*
X20000Y240000D03*
Y200000D03*
Y220000D03*
X5500Y260982D03*
Y240982D03*
Y220982D03*
Y200982D03*
X23426Y281496D03*
X24764Y286496D03*
X28426Y290197D03*
X38465D03*
X42166Y286496D03*
X5500Y320982D03*
Y300982D03*
Y280982D03*
X20000Y380000D03*
Y400000D03*
X5500Y400982D03*
Y380982D03*
Y360982D03*
Y340982D03*
X20000Y340000D03*
Y460000D03*
Y440000D03*
Y480000D03*
Y420000D03*
X5500Y480982D03*
Y460982D03*
Y440982D03*
Y420982D03*
X20000Y540000D03*
Y500000D03*
Y520000D03*
X5500Y540982D03*
Y520982D03*
Y500982D03*
X24500Y624897D03*
Y612249D03*
Y599700D03*
X16500Y624765D03*
Y618765D03*
Y612166D03*
Y606166D03*
Y598197D03*
X24500Y700488D03*
Y687889D03*
Y675291D03*
Y662693D03*
Y637496D03*
X16500Y700355D03*
Y694355D03*
Y687757D03*
Y681757D03*
Y675158D03*
Y669158D03*
Y662226D03*
Y657000D03*
Y649500D03*
Y644530D03*
Y637363D03*
Y631363D03*
X24500Y769579D03*
Y756981D03*
Y725485D03*
Y712886D03*
X16500Y769646D03*
Y763646D03*
Y757048D03*
Y725552D03*
Y719552D03*
Y712953D03*
Y706953D03*
Y751658D03*
Y732500D03*
X24500Y841820D03*
Y829422D03*
Y816823D03*
Y804225D03*
Y791626D03*
X16500Y848686D03*
Y842087D03*
Y836087D03*
Y829489D03*
Y823489D03*
Y816891D03*
Y810891D03*
Y804292D03*
Y798292D03*
Y791694D03*
Y785694D03*
Y777725D03*
X24500Y905012D03*
Y892414D03*
Y879665D03*
Y867017D03*
Y854419D03*
X16500Y917678D03*
Y911678D03*
Y905079D03*
Y899079D03*
Y879883D03*
Y873883D03*
Y867284D03*
Y861284D03*
Y854686D03*
Y889500D03*
X36000Y960000D03*
X20000Y980000D03*
Y960000D03*
Y940000D03*
X16000Y931000D03*
X34500Y925000D03*
X5500Y980299D03*
X36500Y999500D03*
X5500Y1040299D03*
Y1020299D03*
Y1000299D03*
X24500Y1102601D03*
Y1115200D03*
X16500Y1140024D03*
Y1120828D03*
Y1114828D03*
Y1108229D03*
Y1102229D03*
Y1133500D03*
Y1094260D03*
X31707Y1086000D03*
X24500Y1203189D03*
Y1190590D03*
Y1177992D03*
Y1165394D03*
Y1152795D03*
Y1140197D03*
X16500Y1209016D03*
Y1203016D03*
Y1196418D03*
Y1190418D03*
Y1183820D03*
Y1177820D03*
Y1171221D03*
Y1165221D03*
Y1158623D03*
Y1152623D03*
Y1146024D03*
X24500Y1285079D03*
Y1272480D03*
Y1259882D03*
Y1228386D03*
Y1215787D03*
X16500Y1284906D03*
Y1278308D03*
Y1272308D03*
Y1265709D03*
Y1259709D03*
Y1253111D03*
Y1247721D03*
Y1221615D03*
Y1215615D03*
Y1228500D03*
X24500Y1357720D03*
Y1345121D03*
Y1332523D03*
Y1319924D03*
Y1297677D03*
X16500Y1357347D03*
Y1350749D03*
Y1344749D03*
Y1338150D03*
Y1332150D03*
Y1325552D03*
Y1319552D03*
Y1303505D03*
Y1297505D03*
Y1290906D03*
X16417Y1311583D03*
X24500Y1407913D03*
Y1395315D03*
Y1382716D03*
Y1370118D03*
X16500Y1413741D03*
Y1407741D03*
Y1401142D03*
Y1395142D03*
Y1388544D03*
Y1382544D03*
Y1375946D03*
Y1369946D03*
Y1363347D03*
X24500Y1560197D03*
Y1547598D03*
Y1522401D03*
Y1535000D03*
X16500Y1573000D03*
Y1566500D03*
Y1560500D03*
Y1554000D03*
Y1548000D03*
Y1541500D03*
Y1535000D03*
Y1529000D03*
Y1521031D03*
Y1512500D03*
X24500Y1632638D03*
Y1620039D03*
Y1607441D03*
Y1594842D03*
Y1582244D03*
X16500Y1644735D03*
Y1639845D03*
Y1633000D03*
Y1626500D03*
Y1620000D03*
Y1614000D03*
Y1607500D03*
Y1601500D03*
Y1595000D03*
Y1588500D03*
Y1582500D03*
X24500Y1717868D03*
Y1695821D03*
Y1683222D03*
Y1670624D03*
X16500Y1669933D03*
Y1677000D03*
Y1683170D03*
Y1689500D03*
Y1696000D03*
Y1702500D03*
Y1712000D03*
Y1717462D03*
Y1665044D03*
X24500Y1755663D03*
Y1743065D03*
Y1730466D03*
X22219Y1768323D03*
X16500Y1749000D03*
Y1756052D03*
Y1765000D03*
Y1774500D03*
Y1784000D03*
Y1790500D03*
Y1724000D03*
Y1730658D03*
Y1736500D03*
Y1743356D03*
X39500Y1823300D03*
X39400Y1819900D03*
X38400Y1846750D03*
X38300Y1859050D03*
X38800Y1810100D03*
X22100Y1802800D03*
X38317Y1804491D03*
X34900Y1807200D03*
X35100Y1813000D03*
X26500Y1805200D03*
X26600Y1810600D03*
X26300Y1815000D03*
X30800Y1805300D03*
Y1810500D03*
X17500Y1801900D03*
X22000Y1814100D03*
Y1809100D03*
X17500Y1806900D03*
Y1811900D03*
Y1816500D03*
X11615Y1922835D03*
X12953Y1927835D03*
X16615Y1931536D03*
X26654D03*
X30355Y1927835D03*
X31693Y1922835D03*
X5500Y1880685D03*
Y1888685D03*
X38500Y1871350D03*
X38200Y1883800D03*
X19974Y1943969D03*
X33700Y1960300D03*
X20000Y1960000D03*
Y1980000D03*
X32559Y1986626D03*
X12559D03*
X5500Y1973685D03*
Y1953685D03*
X40000Y40000D03*
Y20000D03*
X90018Y5500D03*
X110018D03*
X50018D03*
X70018D03*
X60000Y80000D03*
X40000D03*
Y100000D03*
Y120000D03*
Y60000D03*
X109038Y68476D03*
X109000Y87476D03*
X109160Y100476D03*
X96000Y114212D03*
Y107913D03*
Y98464D03*
Y89015D03*
Y79567D03*
Y70118D03*
Y60868D03*
X96100Y52300D03*
X72500Y91161D03*
Y86161D03*
X100000Y180000D03*
X99800Y194200D03*
X40000Y160000D03*
Y180000D03*
Y140000D03*
X67500Y135830D03*
X108917Y156976D03*
X72500Y166161D03*
X96000Y158307D03*
X72500Y151161D03*
X96000Y148858D03*
X72500Y136161D03*
X96000Y139409D03*
Y134000D03*
Y123661D03*
X104000Y125000D03*
X85250Y247238D03*
X80000Y200000D03*
X77306Y259381D03*
X40000Y240000D03*
Y200000D03*
Y220000D03*
X43504Y281496D03*
X109044Y473988D03*
X96000Y485079D03*
Y475630D03*
Y466181D03*
Y456732D03*
X67500Y541342D03*
X109000Y492988D03*
X109138Y511488D03*
X72500Y556673D03*
X96000Y554369D03*
X72500Y541673D03*
X96000Y544921D03*
Y539500D03*
Y529173D03*
Y519724D03*
Y513425D03*
Y503976D03*
Y494527D03*
X72500Y496673D03*
Y491673D03*
X104000Y531000D03*
X61100Y600100D03*
X80000Y600000D03*
X108917Y562488D03*
X72500Y571673D03*
X96000Y563819D03*
X85250Y652750D03*
X61500Y682500D03*
X102500Y737500D03*
X83200Y768300D03*
X76000Y706500D03*
X67500Y822500D03*
X51000Y913500D03*
X63500Y899000D03*
X65500Y867500D03*
X109040Y879500D03*
X109000Y898500D03*
X109187Y917000D03*
X96000Y918937D03*
Y909488D03*
Y900039D03*
Y890591D03*
Y881142D03*
Y871692D03*
Y862244D03*
X72500Y902185D03*
Y897185D03*
X67000Y953500D03*
X96532Y977682D03*
X107400Y994000D03*
X67500Y946855D03*
X109000Y968000D03*
X72500Y977185D03*
X96000Y969331D03*
X72500Y962185D03*
X96000Y959882D03*
X72500Y947185D03*
X96000Y950433D03*
Y945000D03*
Y934685D03*
Y925236D03*
X104000Y936000D03*
X99600Y1001400D03*
X102403Y1058209D03*
X103200Y1042500D03*
X71000Y1109000D03*
X111500Y1145000D03*
X109040Y1285012D03*
X96000Y1277205D03*
Y1267756D03*
X67500Y1352366D03*
X109000Y1304012D03*
X109133Y1322512D03*
X72500Y1352697D03*
X96000Y1355945D03*
Y1350500D03*
Y1340197D03*
Y1330748D03*
Y1324449D03*
Y1315000D03*
Y1305551D03*
Y1296103D03*
Y1286654D03*
X72500Y1307697D03*
Y1302697D03*
X104000Y1341000D03*
X109000Y1373512D03*
X70838Y1384165D03*
X96000Y1374843D03*
X72285Y1365633D03*
X96000Y1365393D03*
X80000Y1480000D03*
X109500Y1486000D03*
X90500Y1521500D03*
X96000Y1541100D03*
X72000Y1551500D03*
X72100Y1536400D03*
Y1509900D03*
X64500Y1581500D03*
X40500Y1608500D03*
X66500Y1694000D03*
X68000Y1651500D03*
X109040Y1690524D03*
X109000Y1709524D03*
X96000Y1701615D03*
Y1711063D03*
Y1673268D03*
X72500Y1708209D03*
X96000Y1682716D03*
Y1692166D03*
X72500Y1713209D03*
X96000Y1720512D03*
X100000Y1780000D03*
X67500Y1746128D03*
X109137Y1728024D03*
X109030Y1772524D03*
X96000Y1729961D03*
Y1736260D03*
Y1745109D03*
Y1755158D03*
Y1761457D03*
Y1770906D03*
X72500Y1758209D03*
Y1773209D03*
Y1788209D03*
X96000Y1780355D03*
X100000Y1759000D03*
X93600Y1848200D03*
X45100Y1850800D03*
X42300Y1846750D03*
X42200Y1859050D03*
X45200Y1839300D03*
Y1843300D03*
Y1854700D03*
X40800Y1832300D03*
Y1827300D03*
X76975Y1864000D03*
X100000Y1928000D03*
X80000D03*
X60000D03*
X74300Y1900000D03*
X107543Y1898024D03*
X111000Y1879570D03*
X100100Y1896300D03*
X80000Y1920000D03*
X60000D03*
Y1900000D03*
X44000D03*
X40556Y1917072D03*
X40000Y1940000D03*
X52000Y1887500D03*
X41700Y1883700D03*
X42100Y1871350D03*
X110700Y1974100D03*
X80000Y1980000D03*
X100300Y1980900D03*
X71666Y1961325D03*
X40000Y1980000D03*
X112559Y1986626D03*
X92559D03*
X72559D03*
X52559D03*
X94700Y1974100D03*
X98800D03*
X103300D03*
X107000D03*
X123819Y17717D03*
X125157Y22717D03*
X128819Y26418D03*
X138858D03*
X142559Y22717D03*
X143897Y17717D03*
X155018Y5500D03*
X170018D03*
X116600Y46800D03*
X180000Y80000D03*
X160000D03*
X140000D03*
X154700Y65000D03*
X150200D03*
X141700Y64900D03*
X138200D03*
X131700Y61300D03*
X128200D03*
X179147Y137913D03*
X180000Y180000D03*
X124000Y135859D03*
Y124059D03*
X147125Y160500D03*
X158300Y135200D03*
X176492Y231103D03*
X180100Y231095D03*
X140000Y247500D03*
X145800Y332400D03*
X131300D03*
X173000Y312500D03*
X131300Y335900D03*
X126445Y338300D03*
X124466Y370025D03*
X143500Y370000D03*
X147000D03*
X139500D03*
X136000D03*
X180000Y480000D03*
Y460000D03*
X120000D03*
X140000Y480000D03*
Y460000D03*
X160000Y440000D03*
X140000D03*
X120800Y438000D03*
X157500Y551200D03*
X160000Y520000D03*
X180000D03*
X124000Y541373D03*
Y529573D03*
X165138Y536500D03*
X174000Y553500D03*
X131500Y610500D03*
X180000Y620000D03*
Y580000D03*
X139500Y600400D03*
X180000Y600000D03*
X132350Y563750D03*
X176492Y636617D03*
X180308D03*
X140000Y654000D03*
X124966Y775525D03*
X125500Y719000D03*
X180000Y720000D03*
X136100Y775600D03*
X139600D03*
X147100D03*
X143600D03*
X145800Y737100D03*
X131400Y738200D03*
X173000Y718000D03*
X131400Y741700D03*
X122445Y743800D03*
X116000Y814500D03*
X122251Y842400D03*
X160000Y880000D03*
X140000Y900000D03*
X180000Y980000D03*
X167000Y945909D03*
Y935909D03*
X180000Y1000000D03*
X176492Y1042129D03*
X180308D03*
X140000Y1059500D03*
X129000Y1051500D03*
X180000Y1140000D03*
X129500Y1084500D03*
X122500Y1107000D03*
X123500Y1123500D03*
X180000Y1120000D03*
Y1100000D03*
Y1080000D03*
X147800Y1140000D03*
X173000Y1123500D03*
X124100Y1181025D03*
X143500Y1180400D03*
X147000D03*
X139500D03*
X136000D03*
X131500Y1143200D03*
Y1146700D03*
X122400Y1149200D03*
X120000Y1280000D03*
X140000D03*
X160000D03*
X180000D03*
X120000Y1220000D03*
X180000D03*
X118250Y1252050D03*
X179147Y1353048D03*
X160000Y1340000D03*
X180000D03*
X140000D03*
Y1300000D03*
X160000D03*
X180000D03*
X129500Y1352321D03*
Y1340521D03*
X121320Y1425396D03*
X117690Y1397168D03*
X143087Y1403623D03*
X180000Y1400000D03*
Y1420000D03*
X160000Y1360000D03*
X151125Y1376608D03*
X126916Y1447364D03*
X180000Y1440000D03*
Y1500000D03*
X176492Y1447634D03*
X180308D03*
X130000Y1470000D03*
X122000D03*
X114000D03*
X140000Y1464000D03*
X147700Y1545500D03*
X123400Y1522600D03*
X116500Y1505500D03*
X180000Y1520000D03*
X130600Y1549100D03*
X173000Y1529000D03*
X123500Y1505200D03*
X144200Y1545500D03*
X113841Y1580900D03*
X181500Y1641500D03*
X182500Y1622500D03*
X172000Y1595000D03*
X171500Y1613500D03*
X143300Y1586900D03*
X146800D03*
X138800Y1585100D03*
X135300D03*
X160200Y1710300D03*
X117300Y1696500D03*
X136600Y1681900D03*
X121700Y1654800D03*
X143000Y1656000D03*
X137000Y1666500D03*
X120000Y1678000D03*
X123000Y1702000D03*
X136700Y1720100D03*
X160000Y1720000D03*
Y1700000D03*
X180000D03*
Y1680000D03*
X117000Y1654600D03*
X159800Y1730000D03*
X148000Y1787000D03*
X125000Y1757834D03*
Y1746034D03*
X128800Y1854000D03*
X145500Y1807500D03*
X136500Y1811500D03*
X140000Y1820000D03*
X160000Y1800000D03*
X180000D03*
Y1840000D03*
X180308Y1853146D03*
X176492D03*
X128800Y1921300D03*
X129500Y1883500D03*
X115228Y1879770D03*
X128200Y1900300D03*
X180000Y1880000D03*
Y1900000D03*
Y1940000D03*
X173000Y1934500D03*
X140000Y1870000D03*
X133000Y1977100D03*
X114200Y1974100D03*
X118500Y1971400D03*
X139100Y1977100D03*
X172559Y1986626D03*
X152559D03*
X132559D03*
X130500Y1946200D03*
X240000Y20000D03*
Y40000D03*
X230018Y5500D03*
X250018D03*
X190018D03*
X210018D03*
X220000Y80000D03*
X240000D03*
X200000D03*
X240000Y140000D03*
X220000D03*
Y160000D03*
X240000D03*
X200000Y180000D03*
X220000D03*
X240000D03*
X200000Y200000D03*
X240000Y220000D03*
X220000D03*
Y200000D03*
X240000D03*
X200000Y260000D03*
X240000D03*
X220000D03*
X194500Y243300D03*
X200000Y280000D03*
X220000D03*
X240000D03*
Y320000D03*
Y300000D03*
X220000D03*
X200000D03*
Y320000D03*
X220000D03*
X240000Y340000D03*
X220000Y360000D03*
X240000D03*
X220000Y340000D03*
X200000D03*
Y360000D03*
X220000Y480000D03*
X200000D03*
X220000Y460000D03*
X200000D03*
X220000Y420000D03*
X200000Y440000D03*
Y420000D03*
Y520000D03*
X220000D03*
X195500Y531250D03*
Y546250D03*
Y538750D03*
X220000Y620000D03*
X240000Y600000D03*
Y580000D03*
X200000D03*
Y700000D03*
X220000D03*
Y680000D03*
X200000D03*
Y660000D03*
X220000D03*
Y640000D03*
X190500Y651513D03*
X240000Y760000D03*
X220000Y720000D03*
Y740000D03*
X200000Y760000D03*
Y740000D03*
Y720000D03*
Y900000D03*
X240000Y860000D03*
X220000D03*
Y880000D03*
X240000D03*
X194200Y985900D03*
X220000Y940000D03*
X240000D03*
X201125Y957200D03*
X195500Y949750D03*
X220000Y1040000D03*
Y1020000D03*
X240000D03*
Y1000000D03*
Y1060000D03*
X220000D03*
X240000Y1040000D03*
X190600Y1057024D03*
X200000Y1080000D03*
Y1100000D03*
Y1140000D03*
Y1120000D03*
X220000Y1140000D03*
Y1120000D03*
X240000D03*
Y1100000D03*
X220000D03*
Y1080000D03*
X240000D03*
X255674Y1099470D03*
X208500Y1190000D03*
X200000Y1200000D03*
X240000D03*
Y1180000D03*
X200000Y1160000D03*
Y1280000D03*
X220000D03*
X240000D03*
Y1220000D03*
X220000D03*
X200000Y1340000D03*
X220000D03*
X240000D03*
X200000Y1300000D03*
X220000D03*
X240000D03*
X227000Y1359500D03*
X215000Y1368000D03*
X240000Y1367500D03*
Y1420000D03*
Y1400000D03*
Y1460000D03*
Y1440000D03*
X200000D03*
Y1460000D03*
Y1480000D03*
X240000D03*
Y1500000D03*
X200000D03*
X190400Y1450738D03*
X202000Y1534000D03*
X200000Y1520000D03*
X220000D03*
X240000D03*
X200000Y1560000D03*
X220000D03*
X240000D03*
X203500Y1618500D03*
X229500Y1614500D03*
X189300Y1577200D03*
X220000Y1580000D03*
X242500Y1702500D03*
X251800Y1718400D03*
X220000Y1720000D03*
X200000Y1660000D03*
Y1680000D03*
X220000D03*
Y1660000D03*
X240000Y1680000D03*
Y1660000D03*
X220200Y1740900D03*
X206000Y1735000D03*
X256000Y1745500D03*
X220000Y1734500D03*
X207600Y1777500D03*
X220800Y1763750D03*
X191353Y1772940D03*
X200000Y1800000D03*
X220000D03*
X240000D03*
X220000Y1840000D03*
X240000D03*
X194620Y1865000D03*
X200000Y1880000D03*
Y1900000D03*
X220000D03*
X240000Y1920000D03*
X220000D03*
X200000D03*
Y1940000D03*
X220000D03*
X240000D03*
X256549Y1898366D03*
X240000Y1880000D03*
X256500D03*
X200000Y1980000D03*
Y1960000D03*
X220000Y1980000D03*
Y1960000D03*
X240000Y1980000D03*
Y1960000D03*
X252559Y1986626D03*
X232559D03*
X212559D03*
X192559D03*
X300000Y40000D03*
Y20000D03*
X320000D03*
Y40000D03*
X260000D03*
Y20000D03*
X280000D03*
Y40000D03*
X310018Y5500D03*
X330018D03*
X270018D03*
X290018D03*
X320000Y80000D03*
X300000Y60000D03*
X320000D03*
Y120000D03*
X300000D03*
X280000D03*
X260000Y100000D03*
X280000D03*
X300000D03*
X320000D03*
X300000Y80000D03*
X280000D03*
X260000D03*
Y160000D03*
X320000D03*
X300000Y140000D03*
X320000D03*
X260000Y180000D03*
X280000D03*
Y220000D03*
X260000D03*
Y200000D03*
X280000D03*
X300000D03*
Y220000D03*
X320000D03*
Y240000D03*
X265552Y279528D03*
X266890Y284528D03*
X270552Y288229D03*
X280591D03*
X284292Y284528D03*
X285630Y279528D03*
X320000Y320000D03*
X300000D03*
X280000D03*
X260000D03*
X320000Y280000D03*
X300000D03*
X260000Y300000D03*
X280000Y360000D03*
X260000D03*
Y340000D03*
X280000D03*
X300000D03*
X320000D03*
X304553Y374081D03*
X313500Y386000D03*
X309000Y365000D03*
X313500Y362000D03*
X320000Y359500D03*
X327500Y373000D03*
X305100Y407700D03*
X304400Y416200D03*
X280000Y460000D03*
Y480000D03*
X300000D03*
Y460000D03*
X320000D03*
X300000Y440000D03*
X280000D03*
Y420000D03*
X260000D03*
Y440000D03*
Y480000D03*
Y460000D03*
X321500Y413000D03*
X260000Y520000D03*
X320000Y540000D03*
X260000Y560000D03*
Y600000D03*
X280000Y620000D03*
X260000D03*
X302500Y583000D03*
X297500D03*
Y588000D03*
X302500D03*
X300000Y585500D03*
X265552Y685030D03*
X266890Y690030D03*
X270552Y693731D03*
X280591D03*
X284292Y690030D03*
X285630Y685030D03*
X298500Y660200D03*
Y680200D03*
X320000Y700000D03*
X260000D03*
X320000Y640000D03*
X300000D03*
X280000D03*
X260000D03*
X298200Y720000D03*
X260000D03*
X320000D03*
X304400Y846700D03*
X321500Y807000D03*
X297840Y804552D03*
X280000Y820000D03*
X325053Y782652D03*
X309000Y795000D03*
X321500Y843000D03*
X323000Y819500D03*
X313500Y792000D03*
X320000Y789500D03*
X327500Y803000D03*
X304500Y836700D03*
X301300Y822550D03*
X260000Y860000D03*
Y880000D03*
X300000D03*
X280000D03*
Y860000D03*
X260000Y940000D03*
X280000D03*
X300000D03*
X260000Y980000D03*
X280000D03*
X300000D03*
X320000Y1060000D03*
X300000D03*
X260000D03*
Y1040000D03*
X280000D03*
X300000D03*
X320000D03*
Y1020000D03*
X280000D03*
X300000D03*
X260000D03*
X280000Y1000000D03*
X300000D03*
X320000D03*
X265552Y1088573D03*
X266890Y1093573D03*
X270552Y1097274D03*
X280591D03*
X284292Y1093573D03*
X285630Y1088573D03*
X320000Y1140000D03*
X260000Y1120000D03*
X280000D03*
X300000D03*
X320000Y1100000D03*
X300000D03*
Y1080000D03*
X320000D03*
X260000Y1200000D03*
X280000D03*
Y1180000D03*
X260000Y1160000D03*
X296011Y1185470D03*
X309000Y1166500D03*
X295400Y1172655D03*
X313500Y1187500D03*
X320000Y1161000D03*
X327500Y1174500D03*
X305200Y1208300D03*
X304500Y1217500D03*
X320000Y1280000D03*
X300000Y1240000D03*
X320000Y1260000D03*
X300000Y1280000D03*
Y1260000D03*
X280000Y1280000D03*
X260000D03*
Y1260000D03*
X280000D03*
Y1220000D03*
X260000D03*
X321500Y1214500D03*
X280000Y1340000D03*
X260000D03*
X300000Y1300000D03*
X280000D03*
X260000D03*
X311500Y1389000D03*
X280000Y1380000D03*
X260000Y1400000D03*
Y1420000D03*
X300000Y1421500D03*
X302500Y1424000D03*
X297500D03*
Y1419000D03*
X302500D03*
X303500Y1389000D03*
X297600Y1392000D03*
X273500Y1407500D03*
X260000Y1440000D03*
X300984Y1433500D03*
X260000Y1520000D03*
X280000D03*
X300000D03*
X320000Y1540000D03*
Y1560000D03*
X300000D03*
X280000D03*
X260000D03*
X258585Y1508386D03*
X260000Y1620000D03*
Y1600000D03*
X300000Y1620000D03*
X280000Y1600000D03*
Y1620000D03*
X300000Y1600000D03*
X320000D03*
X289300Y1696200D03*
Y1701800D03*
X306200Y1689400D03*
X259000Y1702500D03*
X260000Y1680000D03*
Y1660000D03*
X321500Y1713000D03*
X327500Y1673000D03*
X305300Y1715700D03*
X306200Y1709600D03*
X320000Y1760000D03*
Y1780000D03*
X260000Y1740000D03*
X288000Y1742500D03*
X293000D03*
X284000Y1731250D03*
X268800Y1774600D03*
X260000Y1800000D03*
Y1840000D03*
X280000D03*
X320000Y1860000D03*
X300000D03*
Y1840000D03*
X320000Y1820000D03*
Y1840000D03*
X271500Y1795000D03*
X279500D03*
X287500D03*
X300000Y1800000D03*
X265552Y1903534D03*
X266890Y1908534D03*
X270552Y1912235D03*
X280591D03*
X284292Y1908534D03*
X285630Y1903534D03*
X320000Y1940000D03*
X300000D03*
X280000D03*
X260000D03*
X280071Y1924667D03*
X300000Y1900000D03*
Y1920000D03*
X320000D03*
Y1900000D03*
X300000Y1880000D03*
X320000D03*
X260000Y1980000D03*
Y1960000D03*
X280000Y1980000D03*
Y1960000D03*
X300000Y1980000D03*
Y1960000D03*
X320000Y1980000D03*
Y1960000D03*
X312559Y1986626D03*
X292559D03*
X272559D03*
X380000Y20000D03*
Y40000D03*
X400000D03*
Y20000D03*
X340000Y40000D03*
Y20000D03*
X360000Y40000D03*
Y20000D03*
X390018Y5500D03*
X350018D03*
X370018D03*
X400000Y100000D03*
Y80000D03*
X377500Y98000D03*
X400000Y60000D03*
X340000Y80000D03*
Y100000D03*
Y60000D03*
X400000Y120000D03*
X340000D03*
X373500Y98000D03*
X363750Y65250D03*
X352500Y68500D03*
X358500Y93500D03*
X363750Y73300D03*
X340000Y180000D03*
X360000D03*
X380000D03*
X400000D03*
Y140000D03*
Y160000D03*
X380000Y140000D03*
Y160000D03*
X360000Y140000D03*
Y160000D03*
X340000D03*
Y140000D03*
X357250Y124000D03*
X400000Y220000D03*
Y200000D03*
X380000D03*
X340000Y240000D03*
Y260000D03*
X360000D03*
Y280000D03*
X370000Y411000D03*
Y405500D03*
X375500D03*
X381000D03*
X375500Y411000D03*
X381000D03*
X359000D03*
X364500D03*
Y405500D03*
X359000D03*
X370000Y400000D03*
X381000D03*
X375500D03*
X370000Y389000D03*
Y394500D03*
X375500D03*
Y389000D03*
X381000D03*
Y394500D03*
X364500Y400000D03*
X365000Y394500D03*
Y389000D03*
X359000D03*
Y394500D03*
Y400000D03*
X337500Y406250D03*
X331500Y393000D03*
X401500Y401500D03*
X397000Y383750D03*
X400000Y440000D03*
Y460000D03*
Y480000D03*
X339500Y416750D03*
X370397Y439122D03*
X368500Y436000D03*
X372000D03*
X397000Y414750D03*
X379250Y451000D03*
X385896Y444265D03*
X343750Y451000D03*
X350241Y444377D03*
X400000Y540000D03*
X340000D03*
X380000Y500000D03*
Y540000D03*
X400000Y520000D03*
Y560000D03*
X360000Y580000D03*
X340000Y560000D03*
Y600000D03*
Y620000D03*
X380000D03*
X400000D03*
X380000Y560000D03*
Y660000D03*
X400000Y640000D03*
Y680000D03*
Y700000D03*
X340000Y660000D03*
Y680000D03*
Y700000D03*
X360000D03*
Y680000D03*
Y660000D03*
Y640000D03*
X380000D03*
X400000Y740000D03*
Y720000D03*
X340000Y740000D03*
Y720000D03*
X360000D03*
X400000Y780000D03*
X340000D03*
X370000Y841000D03*
Y835500D03*
X375500D03*
X381000D03*
X375500Y841000D03*
X381000D03*
X359000D03*
X364500D03*
Y835500D03*
X359000D03*
X370000Y830000D03*
X381000D03*
X375500D03*
X370000Y819000D03*
Y824500D03*
X375500D03*
Y819000D03*
X381000D03*
Y824500D03*
X364500Y830000D03*
X365000Y824500D03*
Y819000D03*
X359000D03*
Y824500D03*
Y830000D03*
X397000Y844750D03*
X339500Y846750D03*
X337500Y836250D03*
X331500Y823000D03*
X401500Y836000D03*
X395000Y806500D03*
X371059Y903347D03*
X355622Y919857D03*
X380000Y920000D03*
X400000D03*
Y900000D03*
X368500Y865000D03*
X372000D03*
X379228Y874277D03*
X387250Y881000D03*
X351740Y880717D03*
X343749Y874298D03*
X335823Y940330D03*
X340000Y980000D03*
X360000D03*
X380000D03*
X400000D03*
Y960000D03*
X380000D03*
X340000D03*
X360000D03*
Y940000D03*
X380000D03*
X400000D03*
Y1060000D03*
X380000D03*
X400000Y1040000D03*
X380000D03*
X360000Y1060000D03*
X340000D03*
X360000Y1040000D03*
X340000D03*
Y1000000D03*
Y1020000D03*
X360000Y1000000D03*
Y1020000D03*
X380000Y1000000D03*
Y1020000D03*
X400000Y1000000D03*
Y1020000D03*
X360000Y1140000D03*
X340000D03*
X380000Y1100000D03*
X400000Y1080000D03*
X380000D03*
X360000Y1100000D03*
X340000D03*
X360000Y1080000D03*
X340000D03*
Y1160000D03*
X354228Y1164233D03*
X370000Y1212500D03*
Y1207000D03*
X375500D03*
X381000D03*
X375500Y1212500D03*
X381000D03*
X359000D03*
X364500D03*
Y1207000D03*
X359000D03*
X370000Y1201500D03*
X381000D03*
X375500D03*
X370000Y1190500D03*
Y1196000D03*
X375500D03*
Y1190500D03*
X381000D03*
Y1196000D03*
X364500Y1201500D03*
X365000Y1196000D03*
Y1190500D03*
X359000D03*
Y1196000D03*
Y1201500D03*
X337500Y1207750D03*
X331500Y1194500D03*
X402000Y1202500D03*
X396750Y1181250D03*
X400000Y1280000D03*
Y1260000D03*
X339500Y1218250D03*
X370200Y1239700D03*
X368500Y1236500D03*
X372000D03*
X343749Y1245719D03*
X351771Y1252213D03*
X379249Y1245782D03*
X387208Y1252212D03*
X391500Y1218500D03*
X400000Y1340000D03*
X380000D03*
Y1320000D03*
X400000D03*
X380000Y1300000D03*
X400000D03*
X360000Y1340000D03*
Y1320000D03*
X340000Y1340000D03*
X380000Y1420000D03*
Y1400000D03*
X400000Y1420000D03*
Y1400000D03*
Y1380000D03*
Y1360000D03*
X380000D03*
Y1380000D03*
X360000D03*
Y1360000D03*
X340000D03*
Y1380000D03*
X380000Y1500000D03*
X360000D03*
X340000Y1480000D03*
Y1460000D03*
X400000D03*
X380000Y1440000D03*
X400000D03*
X360000Y1560000D03*
X400000Y1540000D03*
X380000D03*
X360000D03*
Y1520000D03*
X380000D03*
X400000D03*
Y1580000D03*
X380000D03*
X334500Y1650000D03*
Y1665000D03*
X380000Y1660000D03*
X400000D03*
X359000Y1705500D03*
Y1700000D03*
Y1694500D03*
Y1689000D03*
X365000D03*
Y1694500D03*
X364500Y1700000D03*
Y1705500D03*
Y1711000D03*
X359000D03*
X381000D03*
X375500D03*
X381000Y1705500D03*
X375500D03*
X381000Y1694500D03*
Y1689000D03*
X375500D03*
Y1694500D03*
X370000D03*
Y1689000D03*
Y1705500D03*
Y1711000D03*
X381000Y1700000D03*
X375500D03*
X370000D03*
X402000Y1701000D03*
X339500Y1716750D03*
X337500Y1706250D03*
X331500Y1695000D03*
X388750Y1673000D03*
X368500Y1768000D03*
X400000Y1760000D03*
X365400Y1734400D03*
X369000Y1734500D03*
X372500D03*
X393000Y1723500D03*
X351750Y1751000D03*
X343709Y1744187D03*
X400000Y1860000D03*
X380000D03*
X360000D03*
X340000D03*
Y1800000D03*
Y1840000D03*
X360000D03*
X380000D03*
X400000D03*
Y1820000D03*
X380000D03*
X360000D03*
X340000D03*
X360000Y1800000D03*
X400000D03*
X380000D03*
X400000Y1940000D03*
X380000D03*
X360000D03*
X340000D03*
Y1900000D03*
Y1920000D03*
X360000D03*
Y1900000D03*
X380000D03*
Y1920000D03*
X400000D03*
Y1900000D03*
X340000Y1880000D03*
X360000D03*
X380000D03*
X400000D03*
X340000Y1980000D03*
Y1960000D03*
X360000Y1980000D03*
Y1960000D03*
X380000Y1980000D03*
Y1960000D03*
X400000Y1980000D03*
Y1960000D03*
X392559Y1986626D03*
X372559D03*
X352559D03*
X332559D03*
X460000Y20000D03*
Y40000D03*
X420000Y20000D03*
Y40000D03*
X440000D03*
Y20000D03*
X470018Y5500D03*
X410018D03*
X430018D03*
X450018D03*
X460000Y100000D03*
X420000D03*
X440000D03*
X460000Y80000D03*
Y60000D03*
X440000D03*
Y80000D03*
X420000D03*
Y60000D03*
X460000Y120000D03*
X440000D03*
X420000D03*
Y180000D03*
X440000D03*
X460000D03*
Y140000D03*
Y160000D03*
X440000D03*
Y140000D03*
X420000D03*
Y160000D03*
Y200000D03*
X460000D03*
X440000D03*
X420000Y220000D03*
X440000D03*
X460000D03*
Y240000D03*
X440000D03*
X420000D03*
Y260000D03*
X440000D03*
X460000D03*
X440000Y280000D03*
X460000D03*
X440000Y320000D03*
X460000D03*
Y300000D03*
X440000Y400000D03*
X460000D03*
Y380000D03*
X440000D03*
Y360000D03*
X460000D03*
Y340000D03*
X440000D03*
X460000Y480000D03*
Y460000D03*
X440000Y480000D03*
Y460000D03*
Y440000D03*
X460000D03*
Y420000D03*
X440000D03*
X420000Y520000D03*
Y540000D03*
X440000D03*
Y520000D03*
X460000D03*
Y500000D03*
X420000D03*
Y620000D03*
X440000Y600000D03*
X460000Y580000D03*
X420000Y600000D03*
X440000Y580000D03*
X420000Y560000D03*
Y700000D03*
X460000Y660000D03*
Y680000D03*
Y700000D03*
X420000Y680000D03*
Y660000D03*
Y720000D03*
Y740000D03*
X460000Y720000D03*
Y760000D03*
X420000D03*
Y840000D03*
X440000D03*
X460000D03*
Y820000D03*
Y800000D03*
Y780000D03*
X420000D03*
Y920000D03*
X440000D03*
X460000D03*
Y900000D03*
X440000D03*
X420000D03*
Y880000D03*
X460000D03*
X440000D03*
X420000Y860000D03*
X440000D03*
X460000D03*
X420000Y980000D03*
X440000D03*
X460000D03*
Y960000D03*
X440000D03*
X420000D03*
Y940000D03*
X440000D03*
X460000D03*
X420000Y1060000D03*
X440000Y1040000D03*
X420000D03*
Y1000000D03*
Y1020000D03*
X440000Y1000000D03*
Y1020000D03*
X460000D03*
Y1000000D03*
X440000Y1120000D03*
X460000D03*
Y1080000D03*
X420000Y1200000D03*
X440000D03*
X460000D03*
Y1160000D03*
Y1180000D03*
X440000Y1160000D03*
Y1180000D03*
X420000Y1160000D03*
Y1180000D03*
Y1280000D03*
Y1240000D03*
X440000D03*
X460000D03*
Y1260000D03*
X440000D03*
X420000D03*
X460000Y1280000D03*
X440000D03*
X420000Y1340000D03*
Y1320000D03*
X440000D03*
Y1340000D03*
X460000D03*
Y1320000D03*
X440000Y1300000D03*
X420000D03*
X460000D03*
X440000Y1420000D03*
X420000D03*
Y1400000D03*
Y1380000D03*
Y1360000D03*
X440000Y1400000D03*
Y1360000D03*
Y1380000D03*
X460000D03*
Y1360000D03*
Y1420000D03*
Y1400000D03*
X440000Y1500000D03*
X420000Y1480000D03*
X440000D03*
Y1460000D03*
X420000D03*
Y1440000D03*
X440000D03*
X460000Y1500000D03*
Y1480000D03*
Y1460000D03*
Y1440000D03*
X420000Y1540000D03*
X460000Y1520000D03*
Y1580000D03*
X440000D03*
X420000D03*
Y1700000D03*
Y1680000D03*
Y1660000D03*
X440000Y1680000D03*
X460000D03*
Y1660000D03*
X420000Y1760000D03*
X406500Y1736500D03*
X440000Y1780000D03*
Y1760000D03*
X460000D03*
Y1780000D03*
X450000Y1803500D03*
X440000Y1860000D03*
X420000D03*
Y1840000D03*
X440000D03*
X420000Y1820000D03*
X460000Y1840000D03*
Y1860000D03*
Y1940000D03*
X440000D03*
X420000D03*
Y1900000D03*
Y1920000D03*
X440000D03*
Y1900000D03*
X460000Y1920000D03*
Y1900000D03*
X420000Y1880000D03*
X440000D03*
X460000D03*
X420000Y1980000D03*
Y1960000D03*
X440000Y1980000D03*
Y1960000D03*
X460000Y1980000D03*
Y1960000D03*
X472559Y1986626D03*
X452559D03*
X432559D03*
X412559D03*
X500000Y40000D03*
X480000D03*
X520000D03*
X530018Y5500D03*
X510018D03*
X490018D03*
X500000Y20000D03*
X480000D03*
X520000D03*
X540000Y40000D03*
Y20000D03*
Y100000D03*
X520000D03*
X500000D03*
X480000D03*
Y120000D03*
X500000D03*
X520000D03*
X480000Y60000D03*
Y80000D03*
X500000D03*
Y60000D03*
X520000D03*
Y80000D03*
X540000Y120000D03*
Y80000D03*
Y60000D03*
X480000Y140000D03*
Y160000D03*
X500000D03*
Y140000D03*
X520000D03*
Y160000D03*
Y180000D03*
X500000D03*
X480000D03*
X540000Y160000D03*
Y140000D03*
Y180000D03*
X520000Y260000D03*
X500000D03*
X520000Y240000D03*
X480000D03*
X500000D03*
Y220000D03*
X480000D03*
Y200000D03*
X500000D03*
X520000D03*
Y220000D03*
X540000Y260000D03*
Y220000D03*
Y240000D03*
Y200000D03*
X500000Y280000D03*
X520000D03*
X480000D03*
Y300000D03*
X500000D03*
X520000D03*
Y320000D03*
X500000D03*
X480000D03*
X540000Y280000D03*
Y300000D03*
Y320000D03*
X500000Y400000D03*
X520000D03*
Y380000D03*
X540000Y400000D03*
Y380000D03*
Y360000D03*
Y340000D03*
X480000Y400000D03*
Y340000D03*
X500000D03*
X520000D03*
Y360000D03*
X500000D03*
X480000D03*
Y380000D03*
Y440000D03*
X500000D03*
X480000Y420000D03*
X500000D03*
X520000D03*
X540000D03*
X520000Y480000D03*
X500000D03*
X480000D03*
Y460000D03*
X500000D03*
X520000D03*
Y440000D03*
X540000Y460000D03*
Y440000D03*
X500000Y500000D03*
X480000D03*
X520000Y520000D03*
X500000Y540000D03*
X540000D03*
X520000Y560000D03*
X540000D03*
Y580000D03*
X500000D03*
Y600000D03*
X520000D03*
X540000D03*
X520000Y580000D03*
X480000Y560000D03*
X540000Y700000D03*
X520000D03*
X500000D03*
X480000D03*
X540000Y680000D03*
X520000D03*
X500000D03*
X480000D03*
X540000Y660000D03*
X520000D03*
X500000D03*
X480000D03*
Y640000D03*
X500000D03*
X520000D03*
X540000D03*
X520000Y720000D03*
X500000D03*
X480000D03*
X540000Y740000D03*
X480000Y760000D03*
X500000D03*
X520000D03*
X540000D03*
X520000Y780000D03*
X500000D03*
X480000D03*
Y800000D03*
X500000D03*
X520000D03*
X480000Y820000D03*
X500000D03*
X520000D03*
X480000Y840000D03*
X500000D03*
X520000D03*
X540000D03*
Y780000D03*
Y800000D03*
Y820000D03*
X520000Y900000D03*
Y920000D03*
X500000D03*
X480000D03*
X520000Y860000D03*
X500000D03*
X480000D03*
Y880000D03*
X500000D03*
X520000D03*
X480000Y900000D03*
X500000D03*
X540000Y920000D03*
Y860000D03*
Y880000D03*
Y900000D03*
X520000Y980000D03*
X500000D03*
X480000D03*
X520000Y940000D03*
X500000D03*
X480000D03*
Y960000D03*
X500000D03*
X520000D03*
X540000Y980000D03*
Y940000D03*
Y960000D03*
X520000Y1060000D03*
X500000D03*
X480000D03*
Y1000000D03*
X500000Y1040000D03*
X520000D03*
X540000Y1060000D03*
Y1040000D03*
X480000Y1080000D03*
X500000D03*
X520000D03*
Y1120000D03*
X500000D03*
X480000D03*
X540000D03*
Y1100000D03*
X520000Y1200000D03*
X500000D03*
X480000D03*
Y1180000D03*
Y1160000D03*
X500000Y1180000D03*
Y1160000D03*
X520000Y1180000D03*
Y1160000D03*
X540000Y1180000D03*
Y1160000D03*
Y1200000D03*
X480000Y1280000D03*
X500000D03*
X520000D03*
X480000Y1260000D03*
X500000D03*
X520000D03*
X500000Y1240000D03*
X480000D03*
X540000Y1280000D03*
Y1220000D03*
X500000Y1340000D03*
X520000D03*
X480000D03*
Y1320000D03*
X500000D03*
X520000D03*
X480000Y1300000D03*
X500000D03*
X520000D03*
X540000Y1340000D03*
Y1320000D03*
Y1300000D03*
X520000Y1420000D03*
X500000D03*
X480000D03*
X520000Y1380000D03*
Y1400000D03*
X500000Y1380000D03*
Y1400000D03*
X480000Y1380000D03*
Y1400000D03*
X500000Y1360000D03*
X520000D03*
X480000D03*
X540000Y1420000D03*
Y1380000D03*
Y1400000D03*
Y1360000D03*
X520000Y1500000D03*
X500000D03*
X480000D03*
X520000Y1440000D03*
Y1460000D03*
Y1480000D03*
X500000Y1440000D03*
Y1460000D03*
Y1480000D03*
X480000Y1440000D03*
Y1460000D03*
Y1480000D03*
X540000Y1500000D03*
Y1440000D03*
Y1460000D03*
Y1480000D03*
X500000Y1560000D03*
X480000Y1520000D03*
X500000D03*
X520000D03*
X540000D03*
X480000Y1580000D03*
X540000Y1680000D03*
X520000D03*
X500000D03*
X480000D03*
Y1700000D03*
Y1660000D03*
Y1720000D03*
X500000D03*
X520000D03*
Y1700000D03*
X500000D03*
X520000Y1660000D03*
X500000D03*
X540000Y1700000D03*
Y1720000D03*
Y1660000D03*
Y1780000D03*
X520000Y1760000D03*
X480000Y1780000D03*
X500000D03*
X520000D03*
X480000Y1760000D03*
X500000D03*
X520000Y1740000D03*
X500000D03*
X480000D03*
X540000Y1760000D03*
Y1740000D03*
Y1820000D03*
Y1840000D03*
Y1860000D03*
X520000D03*
X480000D03*
X500000Y1840000D03*
X520000D03*
X500000Y1820000D03*
X480000D03*
X520000D03*
X540000Y1940000D03*
X500000D03*
X520000D03*
X480000D03*
X520000Y1920000D03*
X500000D03*
X480000D03*
X520000Y1900000D03*
X500000D03*
X480000D03*
Y1880000D03*
X500000D03*
X520000D03*
X540000Y1900000D03*
Y1880000D03*
Y1920000D03*
X492559Y1986626D03*
X512559D03*
X532559D03*
X520000Y1960000D03*
Y1980000D03*
X500000Y1960000D03*
Y1980000D03*
X480000Y1960000D03*
Y1980000D03*
X540000Y1960000D03*
Y1980000D03*
X580000Y40000D03*
X560000D03*
X600000D03*
X590018Y5500D03*
X570018D03*
X550018D03*
X580000Y20000D03*
X560000D03*
X600000D03*
X620000Y40000D03*
X610018Y5500D03*
X620000Y20000D03*
Y100000D03*
X600000D03*
X580000D03*
X560000D03*
Y120000D03*
X580000D03*
X600000D03*
X560000Y60000D03*
Y80000D03*
X580000D03*
Y60000D03*
X600000D03*
Y80000D03*
X620000Y120000D03*
Y80000D03*
Y60000D03*
X560000Y140000D03*
Y160000D03*
X580000D03*
Y140000D03*
X600000D03*
Y160000D03*
Y180000D03*
X580000D03*
X560000D03*
X620000Y160000D03*
Y140000D03*
Y180000D03*
X580000Y260000D03*
X600000D03*
X620000D03*
X560000D03*
X600000Y200000D03*
Y220000D03*
X580000D03*
Y200000D03*
X560000D03*
Y220000D03*
Y240000D03*
X580000D03*
X600000D03*
X620000D03*
Y220000D03*
Y200000D03*
X560000Y320000D03*
X580000D03*
X600000D03*
X620000D03*
X560000Y300000D03*
X580000D03*
X600000D03*
X620000D03*
X580000Y280000D03*
X600000D03*
X620000D03*
X560000D03*
X620000Y400000D03*
X600000D03*
X580000D03*
X560000D03*
Y380000D03*
X580000D03*
X600000D03*
X620000D03*
X560000Y360000D03*
X580000D03*
X600000D03*
X620000D03*
X560000Y340000D03*
X580000D03*
X600000D03*
X620000D03*
X600000Y480000D03*
X620000D03*
Y460000D03*
X580000Y440000D03*
X560000D03*
X620000Y420000D03*
X600000D03*
X580000D03*
X560000D03*
Y460000D03*
X620000Y520000D03*
X600000D03*
X580000D03*
Y500000D03*
X600000Y540000D03*
Y500000D03*
X620000D03*
X580000Y540000D03*
X560000D03*
X620000D03*
Y560000D03*
X580000D03*
X600000D03*
X560000D03*
Y580000D03*
X600000D03*
X620000Y600000D03*
X600000D03*
X580000D03*
Y580000D03*
X620000D03*
Y640000D03*
X600000D03*
X580000D03*
X560000D03*
X620000Y700000D03*
X600000D03*
X580000D03*
X560000D03*
X620000Y680000D03*
X600000D03*
X580000D03*
X560000D03*
X620000Y660000D03*
X600000D03*
X580000D03*
X560000D03*
Y740000D03*
X580000D03*
X600000D03*
X620000D03*
X580000Y760000D03*
X600000D03*
X620000D03*
X560000D03*
X580000Y780000D03*
X600000D03*
X620000D03*
X580000Y800000D03*
X600000D03*
X620000D03*
X580000Y820000D03*
X600000D03*
X620000D03*
X560000Y840000D03*
X580000D03*
X600000D03*
X560000Y780000D03*
Y800000D03*
X620000Y840000D03*
X600000Y920000D03*
X580000D03*
X560000D03*
X600000Y860000D03*
X580000D03*
X560000D03*
Y900000D03*
Y880000D03*
X580000D03*
Y900000D03*
X600000D03*
Y880000D03*
X620000Y920000D03*
Y880000D03*
Y900000D03*
Y860000D03*
X600000Y980000D03*
X580000D03*
X560000D03*
X580000Y940000D03*
X560000D03*
Y960000D03*
X580000D03*
X600000D03*
Y940000D03*
X620000D03*
Y960000D03*
Y980000D03*
X600000Y1060000D03*
X580000D03*
X560000D03*
Y1040000D03*
X580000D03*
X600000D03*
X620000D03*
Y1060000D03*
X560000Y1100000D03*
X580000D03*
X600000D03*
Y1120000D03*
X580000D03*
X560000D03*
X620000D03*
Y1100000D03*
X560000Y1180000D03*
X580000D03*
Y1160000D03*
X600000Y1180000D03*
Y1160000D03*
Y1200000D03*
X580000D03*
X560000D03*
X620000D03*
Y1160000D03*
Y1180000D03*
X580000Y1260000D03*
Y1240000D03*
X560000D03*
X600000Y1220000D03*
X580000D03*
X560000D03*
X600000Y1260000D03*
Y1240000D03*
X620000Y1280000D03*
Y1220000D03*
Y1240000D03*
Y1260000D03*
X560000Y1340000D03*
X580000D03*
X600000D03*
X560000Y1320000D03*
X580000D03*
X560000Y1300000D03*
X620000D03*
X600000Y1420000D03*
X580000D03*
X560000D03*
X600000Y1400000D03*
X580000Y1380000D03*
Y1400000D03*
X560000Y1380000D03*
Y1400000D03*
X580000Y1360000D03*
X600000D03*
X620000Y1420000D03*
Y1400000D03*
Y1380000D03*
Y1360000D03*
X600000Y1500000D03*
X580000D03*
X560000D03*
X600000Y1440000D03*
Y1460000D03*
Y1480000D03*
X580000Y1440000D03*
Y1460000D03*
Y1480000D03*
X560000Y1440000D03*
Y1460000D03*
Y1480000D03*
X620000Y1500000D03*
Y1480000D03*
Y1460000D03*
Y1440000D03*
X560000Y1520000D03*
X580000D03*
X620000Y1680000D03*
X560000D03*
X580000D03*
X600000D03*
Y1700000D03*
Y1720000D03*
X580000D03*
Y1700000D03*
X560000D03*
Y1720000D03*
X600000Y1660000D03*
X580000D03*
X560000D03*
X620000Y1700000D03*
Y1720000D03*
Y1660000D03*
Y1780000D03*
X600000D03*
X580000D03*
X560000D03*
X620000Y1760000D03*
X600000D03*
X580000D03*
X560000D03*
X620000Y1740000D03*
X600000D03*
X580000D03*
X560000D03*
Y1840000D03*
Y1860000D03*
X620000Y1800000D03*
X600000D03*
X580000D03*
X560000D03*
X620000Y1840000D03*
X600000D03*
X580000D03*
X620000Y1860000D03*
X600000D03*
X580000D03*
X560000Y1940000D03*
X580000D03*
X600000D03*
X620000D03*
X560000Y1880000D03*
X620000D03*
X600000D03*
X580000D03*
X620000Y1900000D03*
X600000D03*
X580000D03*
X620000Y1920000D03*
X600000D03*
X580000D03*
X560000D03*
Y1900000D03*
X620000Y1960000D03*
X600000D03*
X580000D03*
X552559Y1986626D03*
X572559D03*
X592559D03*
X600000Y1980000D03*
X580000D03*
X560000D03*
Y1960000D03*
X612559Y1986626D03*
X620000Y1980000D03*
X660000Y40000D03*
X640000D03*
X670018Y5500D03*
X650018D03*
X630018D03*
X660000Y20000D03*
X640000D03*
X680000D03*
Y40000D03*
X690018Y5500D03*
X680000Y100000D03*
X660000D03*
X640000D03*
Y120000D03*
X660000D03*
X640000Y60000D03*
Y80000D03*
X660000D03*
Y60000D03*
X680000Y120000D03*
Y60000D03*
Y80000D03*
X640000Y140000D03*
Y160000D03*
X660000D03*
Y140000D03*
Y180000D03*
X640000D03*
X680000Y140000D03*
Y160000D03*
Y180000D03*
X660000Y260000D03*
X640000D03*
Y240000D03*
X660000D03*
Y220000D03*
Y200000D03*
X640000Y220000D03*
Y200000D03*
X680000Y260000D03*
Y240000D03*
Y220000D03*
Y200000D03*
X640000Y320000D03*
X660000D03*
X680000D03*
X640000Y300000D03*
X660000D03*
X680000D03*
X640000Y280000D03*
X660000D03*
X680000D03*
X640000Y400000D03*
Y380000D03*
X660000D03*
X640000Y360000D03*
X660000D03*
X680000D03*
X640000Y340000D03*
X660000D03*
X680000D03*
Y480000D03*
Y460000D03*
Y440000D03*
X640000Y480000D03*
X660000D03*
Y460000D03*
X640000D03*
X660000Y440000D03*
X640000D03*
X680000Y420000D03*
X660000Y520000D03*
X640000D03*
X680000D03*
Y500000D03*
X640000D03*
X660000D03*
X640000Y540000D03*
X660000D03*
X680000D03*
Y560000D03*
X660000D03*
X640000D03*
X680000Y600000D03*
X660000D03*
X640000D03*
Y580000D03*
X660000D03*
X680000D03*
Y660000D03*
Y680000D03*
X640000Y640000D03*
Y700000D03*
X660000Y680000D03*
X640000D03*
X660000Y660000D03*
X640000D03*
X660000Y640000D03*
X680000D03*
X640000Y720000D03*
X660000D03*
X680000D03*
X640000Y740000D03*
X660000D03*
X680000D03*
X640000Y760000D03*
X660000D03*
X680000D03*
X640000Y780000D03*
X660000D03*
X680000D03*
X640000Y800000D03*
X660000D03*
X680000D03*
X640000Y820000D03*
X660000D03*
X680000D03*
X640000Y840000D03*
X660000D03*
X680000D03*
X640000Y920000D03*
X660000D03*
X640000Y900000D03*
X660000D03*
X640000Y880000D03*
X660000D03*
X640000Y860000D03*
X660000D03*
X680000Y920000D03*
Y900000D03*
Y880000D03*
Y860000D03*
X640000Y940000D03*
Y960000D03*
X660000D03*
Y980000D03*
X640000D03*
X680000D03*
Y960000D03*
X660000Y1040000D03*
X640000D03*
Y1060000D03*
X680000Y1040000D03*
X640000Y1100000D03*
Y1120000D03*
X660000D03*
Y1100000D03*
X680000D03*
Y1120000D03*
Y1080000D03*
X640000Y1200000D03*
X660000D03*
Y1160000D03*
X640000D03*
Y1180000D03*
X680000Y1160000D03*
Y1200000D03*
X640000Y1280000D03*
X660000D03*
Y1220000D03*
X640000D03*
Y1240000D03*
X660000D03*
X640000Y1260000D03*
X660000D03*
X680000Y1240000D03*
Y1260000D03*
Y1280000D03*
Y1220000D03*
X660000Y1340000D03*
X640000Y1300000D03*
X660000D03*
Y1320000D03*
X640000D03*
X680000Y1340000D03*
Y1300000D03*
Y1320000D03*
X660000Y1420000D03*
X640000D03*
Y1400000D03*
X660000D03*
X640000Y1380000D03*
X680000Y1420000D03*
Y1360000D03*
X660000Y1500000D03*
X640000D03*
X660000Y1480000D03*
X640000D03*
Y1460000D03*
Y1440000D03*
X660000D03*
X680000Y1500000D03*
Y1480000D03*
Y1440000D03*
X640000Y1680000D03*
X660000D03*
X680000D03*
Y1720000D03*
X640000Y1700000D03*
X660000D03*
Y1720000D03*
X640000D03*
Y1660000D03*
X660000D03*
X680000Y1780000D03*
X660000D03*
X640000D03*
X680000Y1760000D03*
X660000D03*
X640000D03*
X680000Y1740000D03*
X660000D03*
X640000D03*
X680000Y1820000D03*
X660000D03*
X680000Y1800000D03*
X660000D03*
X640000D03*
X680000Y1860000D03*
X660000Y1840000D03*
X640000D03*
Y1860000D03*
X660000D03*
X680000Y1880000D03*
Y1900000D03*
Y1920000D03*
X660000Y1880000D03*
X640000D03*
X660000Y1900000D03*
X640000D03*
X660000Y1920000D03*
X640000D03*
Y1940000D03*
X660000D03*
X680000Y1960000D03*
X660000D03*
X640000D03*
X632559Y1986626D03*
X652559D03*
X672559D03*
X660000Y1980000D03*
X640000D03*
X680000D03*
X692559Y1986626D03*
X700000Y20000D03*
X740000Y40000D03*
X750018Y5500D03*
X730018D03*
X710018D03*
X740000Y20000D03*
X720000D03*
X760000Y40000D03*
Y20000D03*
X700000Y120000D03*
X720000D03*
X740000D03*
X700000Y80000D03*
Y60000D03*
Y100000D03*
X720000D03*
Y60000D03*
X740000D03*
Y80000D03*
X720000D03*
X740000Y100000D03*
X760000Y120000D03*
Y100000D03*
Y80000D03*
Y60000D03*
X700000Y180000D03*
X740000D03*
X720000D03*
Y140000D03*
Y160000D03*
X760000D03*
X740000D03*
X700000D03*
Y140000D03*
X740000D03*
X760000D03*
Y180000D03*
X700000Y260000D03*
Y240000D03*
Y220000D03*
Y200000D03*
X720000Y260000D03*
Y240000D03*
Y220000D03*
Y200000D03*
X740000Y260000D03*
Y200000D03*
Y220000D03*
Y240000D03*
X760000Y260000D03*
Y200000D03*
Y220000D03*
Y240000D03*
Y320000D03*
X700000D03*
Y300000D03*
Y280000D03*
X720000Y320000D03*
Y300000D03*
Y280000D03*
X740000D03*
Y300000D03*
X760000Y280000D03*
X740000Y400000D03*
X720000D03*
X700000D03*
X740000Y380000D03*
X720000D03*
X760000Y400000D03*
Y360000D03*
Y380000D03*
Y460000D03*
Y480000D03*
X740000D03*
X720000D03*
X700000D03*
Y420000D03*
X720000D03*
X740000D03*
Y440000D03*
X720000D03*
X700000D03*
Y460000D03*
X720000D03*
X740000D03*
X760000Y420000D03*
Y440000D03*
X720000Y520000D03*
X700000D03*
X740000Y500000D03*
X720000D03*
X740000Y520000D03*
X700000Y500000D03*
Y540000D03*
X740000D03*
X720000D03*
X760000D03*
Y520000D03*
Y500000D03*
Y560000D03*
X720000D03*
X740000D03*
X700000D03*
X740000Y600000D03*
Y580000D03*
X720000D03*
X740000Y620000D03*
X720000D03*
X700000Y580000D03*
Y600000D03*
X720000D03*
X760000Y620000D03*
Y600000D03*
Y580000D03*
Y680000D03*
Y640000D03*
X740000D03*
Y680000D03*
X720000D03*
X700000D03*
Y660000D03*
X720000D03*
X740000D03*
X700000Y640000D03*
X720000D03*
X700000Y720000D03*
X720000D03*
X740000D03*
Y760000D03*
X720000D03*
X700000D03*
Y740000D03*
X720000D03*
X740000D03*
X760000Y760000D03*
Y740000D03*
Y720000D03*
X740000Y840000D03*
X700000D03*
X720000D03*
X740000Y800000D03*
X720000D03*
X700000D03*
Y820000D03*
X720000D03*
X740000D03*
X700000Y780000D03*
X720000D03*
X740000D03*
X760000Y840000D03*
Y800000D03*
Y820000D03*
Y780000D03*
X740000Y920000D03*
X700000D03*
X720000D03*
X740000Y900000D03*
Y880000D03*
Y860000D03*
X700000Y900000D03*
X720000D03*
X700000Y880000D03*
X720000D03*
X700000Y860000D03*
X720000D03*
X760000Y920000D03*
Y900000D03*
Y880000D03*
Y860000D03*
X700000Y980000D03*
X720000D03*
X740000D03*
X700000Y960000D03*
X720000D03*
X740000D03*
X760000Y980000D03*
Y960000D03*
X740000Y1040000D03*
X720000D03*
X700000D03*
X760000D03*
X700000Y1120000D03*
Y1100000D03*
X720000Y1120000D03*
X740000D03*
Y1080000D03*
X700000D03*
X760000Y1120000D03*
X740000Y1160000D03*
X720000D03*
X700000D03*
Y1200000D03*
X720000D03*
X740000D03*
X760000Y1160000D03*
Y1200000D03*
X700000Y1240000D03*
X740000Y1260000D03*
X720000D03*
X700000D03*
X740000Y1280000D03*
X720000D03*
X700000D03*
Y1220000D03*
X720000D03*
X740000D03*
Y1240000D03*
X720000D03*
X760000D03*
Y1260000D03*
Y1280000D03*
Y1220000D03*
X740000Y1340000D03*
X720000D03*
X700000D03*
X740000Y1300000D03*
X720000D03*
X700000D03*
Y1320000D03*
X740000D03*
X720000D03*
X760000Y1340000D03*
Y1300000D03*
Y1320000D03*
X740000Y1420000D03*
X720000D03*
X740000Y1380000D03*
Y1360000D03*
X720000Y1380000D03*
Y1360000D03*
X700000Y1380000D03*
Y1360000D03*
X760000Y1420000D03*
Y1380000D03*
Y1360000D03*
X700000Y1500000D03*
X740000Y1440000D03*
X720000D03*
X700000D03*
X740000Y1480000D03*
X720000D03*
X700000D03*
X760000Y1440000D03*
Y1480000D03*
X740000Y1520000D03*
X720000D03*
X760000D03*
X700000Y1680000D03*
X740000Y1700000D03*
X720000D03*
Y1720000D03*
X740000D03*
Y1680000D03*
X720000D03*
X760000Y1720000D03*
X700000Y1780000D03*
Y1760000D03*
Y1740000D03*
X720000Y1780000D03*
X740000Y1740000D03*
X760000Y1780000D03*
Y1740000D03*
X758000Y1756000D03*
X759700Y1817500D03*
X700000Y1820000D03*
Y1800000D03*
Y1860000D03*
X720000D03*
X740000D03*
X720000Y1800000D03*
X740000D03*
Y1820000D03*
X720000D03*
X759700Y1837500D03*
X720000Y1880000D03*
X740000Y1900000D03*
Y1880000D03*
X700000D03*
Y1900000D03*
Y1920000D03*
X720000Y1940000D03*
Y1900000D03*
Y1920000D03*
X700000Y1940000D03*
X760000Y1880000D03*
Y1940000D03*
X720000Y1960000D03*
X700000D03*
X720000Y1980000D03*
X700000D03*
X712559Y1986626D03*
X732559D03*
X740000Y1960000D03*
Y1980000D03*
X752559Y1986626D03*
X759900Y1959200D03*
X760000Y1980000D03*
X800000Y40000D03*
X820000D03*
X840000D03*
X780000D03*
X810018Y5500D03*
X790018D03*
X770018D03*
X780000Y20000D03*
X800000D03*
X820000D03*
X830018Y5500D03*
X840000Y20000D03*
X800000Y120000D03*
X820000D03*
X840000D03*
X800000Y100000D03*
X820000D03*
X840000D03*
X800000Y80000D03*
X820000D03*
X840000D03*
X800000Y60000D03*
X820000D03*
X840000D03*
X780000Y120000D03*
Y60000D03*
Y80000D03*
Y100000D03*
Y160000D03*
X840000Y140000D03*
X820000D03*
X800000D03*
X816000Y187000D03*
X780000Y140000D03*
Y180000D03*
X828500Y171000D03*
X840000Y174250D03*
X820500Y171000D03*
X820000Y260000D03*
X780000Y200000D03*
Y220000D03*
Y240000D03*
X800000Y220000D03*
Y240000D03*
X820000Y220000D03*
X840000Y240000D03*
X828000Y203000D03*
X780000Y300000D03*
X800000Y280000D03*
Y340000D03*
X780000D03*
Y380000D03*
Y360000D03*
Y400000D03*
X820000D03*
X800000D03*
Y380000D03*
Y360000D03*
X840000Y400000D03*
X780000Y440000D03*
Y420000D03*
Y460000D03*
X800000Y480000D03*
X820000Y420000D03*
Y440000D03*
Y460000D03*
X800000D03*
Y440000D03*
Y420000D03*
X820000Y480000D03*
X780000D03*
X840000D03*
Y420000D03*
Y440000D03*
Y460000D03*
X780000Y540000D03*
X800000D03*
X820000D03*
X780000Y500000D03*
X820000D03*
Y520000D03*
X800000Y500000D03*
Y520000D03*
X780000D03*
X840000Y500000D03*
Y520000D03*
Y540000D03*
X780000Y580000D03*
Y560000D03*
X800000Y600000D03*
Y580000D03*
Y560000D03*
X780000Y620000D03*
X800000D03*
X820000D03*
X780000Y600000D03*
X820000Y580000D03*
Y560000D03*
Y600000D03*
X840000Y620000D03*
Y580000D03*
Y560000D03*
Y600000D03*
X820000Y700000D03*
X780000D03*
X778400Y659800D03*
X800000Y640000D03*
X780000D03*
X820000Y660000D03*
X798400Y659800D03*
X840000Y640000D03*
Y680000D03*
Y660000D03*
Y700000D03*
X820000Y720000D03*
X800000Y760000D03*
X780000D03*
Y740000D03*
X800000D03*
Y720000D03*
X780000D03*
X840000D03*
X780000Y840000D03*
X800000D03*
X820000D03*
Y820000D03*
X780000Y800000D03*
Y780000D03*
X800000D03*
X840000Y840000D03*
Y800000D03*
Y820000D03*
X780000Y920000D03*
X800000D03*
X820000D03*
X780000Y900000D03*
X800000D03*
X820000D03*
X780000Y880000D03*
X800000D03*
X820000D03*
X780000Y860000D03*
X800000D03*
X820000D03*
X840000Y920000D03*
Y860000D03*
Y880000D03*
Y900000D03*
X780000Y980000D03*
X800000D03*
X820000D03*
X780000Y960000D03*
X800000D03*
X820000D03*
X840000D03*
Y980000D03*
X800000Y1060000D03*
X820000D03*
X780000D03*
X820000Y1040000D03*
X840000Y1060000D03*
Y1040000D03*
X780000Y1120000D03*
X800000D03*
Y1080000D03*
Y1100000D03*
X820000Y1120000D03*
X800000Y1200000D03*
X820000D03*
X780000Y1160000D03*
X800000D03*
X780000Y1200000D03*
X840000D03*
X820000Y1220000D03*
Y1240000D03*
X800000D03*
X780000D03*
X820000Y1260000D03*
X800000D03*
X780000D03*
X820000Y1280000D03*
X800000D03*
X780000D03*
Y1220000D03*
X800000D03*
X840000Y1280000D03*
Y1220000D03*
Y1240000D03*
Y1260000D03*
X820000Y1340000D03*
X800000D03*
X780000D03*
X820000Y1300000D03*
X800000D03*
X780000D03*
Y1320000D03*
X820000D03*
X800000D03*
X840000Y1340000D03*
Y1300000D03*
Y1320000D03*
X820000Y1420000D03*
X800000D03*
X780000D03*
X820000Y1380000D03*
Y1360000D03*
X800000Y1380000D03*
Y1360000D03*
X780000Y1380000D03*
Y1360000D03*
X840000Y1420000D03*
Y1360000D03*
Y1380000D03*
X820000Y1440000D03*
X800000D03*
X780000D03*
X820000Y1480000D03*
X800000D03*
X780000D03*
X840000Y1440000D03*
Y1480000D03*
X800000Y1560000D03*
X780000Y1520000D03*
X840000Y1640000D03*
Y1600000D03*
X820000Y1680000D03*
X840000D03*
Y1660000D03*
X780000Y1780000D03*
X800000D03*
Y1740000D03*
X780000D03*
X795500Y1755000D03*
X837500Y1785000D03*
X829500D03*
X819000D03*
X816000Y1801000D03*
X780000Y1800000D03*
X800000D03*
X780000Y1840000D03*
X800000Y1820000D03*
X820000D03*
X828000Y1862000D03*
X827500Y1817000D03*
X800000Y1920000D03*
X820000D03*
X780000D03*
X820000Y1980000D03*
X772559Y1986626D03*
X792559D03*
X812559D03*
X769239Y1955776D03*
X780000Y1980000D03*
X800000D03*
X823400Y1973400D03*
X827900D03*
X835900Y1973500D03*
X839400D03*
X832559Y1986626D03*
X840000Y1980000D03*
X799205Y1960532D03*
X860000Y40000D03*
X880000D03*
X890018Y5500D03*
X870018D03*
X850018D03*
X880000Y20000D03*
X860000D03*
X900000Y40000D03*
X910018Y5500D03*
X900000Y20000D03*
X860000Y120000D03*
X880000D03*
X860000Y100000D03*
X880000D03*
X860000Y80000D03*
X880000D03*
X860000Y60000D03*
X880000D03*
X900000Y120000D03*
Y60000D03*
Y100000D03*
Y80000D03*
X860000Y140000D03*
X908493Y136513D03*
X880000Y180000D03*
X869250Y144750D03*
X885993Y134893D03*
X860000Y260000D03*
Y240000D03*
X908654Y231105D03*
X904838D03*
X872500Y241500D03*
X860100Y336500D03*
X873600Y332200D03*
X860100Y333000D03*
X901500Y312500D03*
X856200Y337300D03*
X865000Y371000D03*
X868500D03*
X876000D03*
X872500D03*
X879600Y385200D03*
X860000Y400000D03*
X880000D03*
X900000D03*
X899900Y382300D03*
X850966Y370025D03*
X880000Y480000D03*
X860000D03*
X880000Y420000D03*
X860000D03*
X880000Y440000D03*
X860000D03*
X880000Y460000D03*
X860000D03*
X900000Y480000D03*
Y420000D03*
Y440000D03*
Y460000D03*
X907493Y542025D03*
X880000Y500000D03*
X860000D03*
X880000Y520000D03*
X860000D03*
X900000Y500000D03*
Y520000D03*
X872875Y535275D03*
X891250Y537500D03*
X860000Y580000D03*
Y560000D03*
X880000Y580000D03*
Y600000D03*
X860000D03*
X900000D03*
X908654Y636613D03*
X904838D03*
X868500Y654000D03*
X859500Y741800D03*
X873400Y738400D03*
X859500Y738300D03*
X901500Y718000D03*
X856100Y743300D03*
X850966Y775525D03*
X860000Y840000D03*
X880000D03*
X864500Y776500D03*
X868000D03*
X872000D03*
X875500D03*
X860000Y800000D03*
X880000D03*
X860000Y820000D03*
X880000D03*
X900000Y840000D03*
Y800000D03*
Y820000D03*
X860000Y920000D03*
X880000D03*
X860000Y860000D03*
X880000D03*
X860000Y880000D03*
X880000D03*
X860000Y900000D03*
X880000D03*
X900000Y920000D03*
Y860000D03*
Y880000D03*
Y900000D03*
X907493Y947537D03*
X860000Y980000D03*
X886517Y945917D03*
X872875Y940925D03*
X880000Y1000000D03*
X860000Y1040000D03*
X908654Y1042129D03*
X904838D03*
X900000Y1000000D03*
Y1040000D03*
Y1020000D03*
X868500Y1059500D03*
X900000Y1080000D03*
X901500Y1123500D03*
X859500Y1147600D03*
X874200Y1144000D03*
X859500Y1144100D03*
X864000Y1181900D03*
X867500D03*
X872200D03*
X875700D03*
X860000Y1200000D03*
X880000D03*
X900000D03*
X854500Y1148700D03*
X850600Y1181025D03*
X860000Y1280000D03*
X880000D03*
X860000Y1220000D03*
Y1240000D03*
Y1260000D03*
X880000Y1220000D03*
Y1240000D03*
Y1260000D03*
X900000Y1280000D03*
Y1220000D03*
Y1240000D03*
Y1260000D03*
X907493Y1353048D03*
X880000Y1340000D03*
X860000D03*
Y1300000D03*
Y1320000D03*
X880000D03*
Y1300000D03*
X900000Y1320000D03*
Y1300000D03*
X872875Y1346488D03*
X891250Y1348500D03*
X860000Y1420000D03*
Y1380000D03*
Y1440000D03*
X908654Y1447641D03*
X904838D03*
X868500Y1465000D03*
X859500Y1553200D03*
X873300Y1549100D03*
X859500Y1549700D03*
X901500Y1529000D03*
X855500Y1554300D03*
X860000Y1640000D03*
Y1580000D03*
X865500Y1589000D03*
X869000D03*
X873000D03*
X876500D03*
X880000Y1599000D03*
X900000Y1600000D03*
X850966Y1586525D03*
X891500Y1712000D03*
X895500D03*
Y1708000D03*
X860000Y1660000D03*
X885750Y1701500D03*
X891500Y1708000D03*
X886600Y1756100D03*
X872875Y1751600D03*
X906500Y1734100D03*
X907493Y1758560D03*
X860000Y1860000D03*
X908654Y1853153D03*
X904838D03*
X860000Y1880000D03*
X901500Y1934500D03*
X867500Y1870000D03*
X843500Y1973500D03*
X847000D03*
X852559Y1986626D03*
X872559D03*
X896546Y1986566D03*
X860000Y1980000D03*
X912559Y1986626D03*
X844800Y1949700D03*
X858800Y1951300D03*
X960000Y40000D03*
X940000D03*
X920000D03*
X950018Y5500D03*
X930018D03*
X920000Y20000D03*
X940000D03*
X960000D03*
X980000Y40000D03*
X970018Y5500D03*
X980000Y20000D03*
X960000Y120000D03*
X940000D03*
X920000D03*
Y60000D03*
X940000D03*
X960000D03*
X920000Y100000D03*
X940000D03*
X960000D03*
Y80000D03*
X940000D03*
X920000D03*
X980000Y120000D03*
Y60000D03*
Y100000D03*
Y80000D03*
X987992Y163376D03*
X960000Y140000D03*
X940000D03*
X960000Y160000D03*
X940000D03*
Y180000D03*
X960000D03*
X980000D03*
X921400Y245200D03*
X940000Y200000D03*
X960000D03*
Y220000D03*
X940000D03*
Y240000D03*
X960000D03*
Y260000D03*
X940000D03*
X980000Y240000D03*
Y260000D03*
Y200000D03*
Y220000D03*
X940000Y280000D03*
X920000D03*
X960000D03*
X920000Y300000D03*
X940000D03*
X960000D03*
X920000Y320000D03*
X940000D03*
X960000D03*
X980000Y280000D03*
Y300000D03*
Y320000D03*
X960000Y400000D03*
X940000D03*
X920000D03*
X960000Y340000D03*
X940000D03*
X920000D03*
Y360000D03*
X940000D03*
X960000D03*
Y380000D03*
X940000D03*
X920000D03*
X980000Y400000D03*
Y340000D03*
Y360000D03*
Y380000D03*
X920000Y480000D03*
X940000D03*
X960000D03*
X920000Y420000D03*
X940000D03*
X960000D03*
X920000Y440000D03*
X940000D03*
X960000D03*
X920000Y460000D03*
X940000D03*
X960000D03*
X980000Y480000D03*
Y420000D03*
Y440000D03*
Y460000D03*
X920000Y500000D03*
X940000D03*
X960000D03*
X920000Y520000D03*
X940000D03*
X960000D03*
Y540000D03*
X980000Y500000D03*
Y520000D03*
Y540000D03*
X940000Y620000D03*
X960000D03*
Y560000D03*
Y580000D03*
Y600000D03*
X940000Y580000D03*
Y600000D03*
X920000Y580000D03*
Y600000D03*
X980000Y620000D03*
Y560000D03*
Y580000D03*
Y600000D03*
X987992Y686998D03*
X920000Y700000D03*
X919000Y651511D03*
X940000Y640000D03*
X960000D03*
X920000Y680000D03*
X940000D03*
X960000D03*
Y660000D03*
X940000D03*
X920000D03*
X940000Y700000D03*
X960000D03*
X980000Y640000D03*
Y660000D03*
Y700000D03*
X940000Y760000D03*
X960000D03*
X920000D03*
Y740000D03*
Y720000D03*
X940000D03*
X960000D03*
X940000Y740000D03*
X960000D03*
X980000Y760000D03*
Y720000D03*
Y740000D03*
X940000Y840000D03*
X960000D03*
X920000D03*
X940000Y780000D03*
X960000D03*
X940000Y800000D03*
X960000D03*
X940000Y820000D03*
X960000D03*
X920000Y800000D03*
Y820000D03*
Y780000D03*
X980000Y840000D03*
Y780000D03*
Y800000D03*
Y820000D03*
X940000Y920000D03*
X960000D03*
X920000D03*
X940000Y860000D03*
X960000D03*
X940000Y880000D03*
X960000D03*
X940000Y900000D03*
X960000D03*
X920000Y860000D03*
Y880000D03*
Y900000D03*
X980000Y920000D03*
Y860000D03*
Y880000D03*
Y900000D03*
X960000Y980000D03*
Y940000D03*
X940000D03*
X960000Y960000D03*
X980000Y980000D03*
Y940000D03*
Y960000D03*
X922900Y1054200D03*
X920000Y1060000D03*
X940000D03*
X960000D03*
Y1000000D03*
X940000D03*
X920000D03*
Y1020000D03*
X940000D03*
X960000D03*
Y1040000D03*
X940000D03*
X920000D03*
X980000Y1000000D03*
Y1020000D03*
Y1040000D03*
X987992Y1082667D03*
X940000Y1140000D03*
X960000D03*
X920000Y1080000D03*
X940000D03*
X960000D03*
Y1100000D03*
X940000D03*
X920000Y1120000D03*
X940000D03*
X960000D03*
X920000Y1140000D03*
X980000D03*
Y1100000D03*
X979962Y1075211D03*
X980000Y1120000D03*
X923000Y1160200D03*
X940000Y1160000D03*
X960000D03*
Y1180000D03*
X940000D03*
X923000Y1180200D03*
X960000Y1200000D03*
X940000D03*
X920000D03*
X980000Y1160000D03*
Y1180000D03*
Y1200000D03*
X960000Y1280000D03*
X940000D03*
X920000D03*
X960000Y1220000D03*
X940000D03*
X960000Y1240000D03*
X940000D03*
X960000Y1260000D03*
X940000D03*
X920000Y1220000D03*
Y1240000D03*
Y1260000D03*
X980000Y1220000D03*
Y1240000D03*
Y1260000D03*
Y1280000D03*
X960000Y1340000D03*
X940000D03*
X920000D03*
X960000Y1300000D03*
X940000D03*
X960000Y1320000D03*
X940000D03*
X920000Y1300000D03*
Y1320000D03*
X980000Y1340000D03*
Y1300000D03*
Y1320000D03*
X981700Y1409000D03*
X954300Y1412600D03*
X960000Y1360000D03*
Y1380000D03*
Y1400000D03*
X940000D03*
X920000D03*
X963500Y1409000D03*
X973000D03*
X968000D03*
X977500D03*
X980000Y1360000D03*
Y1380000D03*
Y1400000D03*
X919000Y1462540D03*
X920000Y1480000D03*
Y1440000D03*
X965000Y1525000D03*
X955000D03*
X945000D03*
Y1516000D03*
X955000D03*
X965000D03*
X935000Y1555000D03*
X945000D03*
X955000D03*
X965000D03*
X920000Y1520000D03*
Y1540000D03*
X935000Y1575000D03*
Y1565000D03*
X945000Y1575000D03*
X955000D03*
X965000D03*
Y1565000D03*
X955000D03*
X945000D03*
X923800Y1559300D03*
X935000Y1545000D03*
Y1535000D03*
Y1525000D03*
Y1516000D03*
X965000Y1545000D03*
X955000D03*
X945000D03*
Y1535000D03*
X955000D03*
X965000D03*
X975000Y1565000D03*
Y1575000D03*
Y1525000D03*
Y1535000D03*
Y1545000D03*
Y1555000D03*
X965000Y1605000D03*
X935000Y1595000D03*
Y1585000D03*
X945000Y1595000D03*
X955000D03*
X965000D03*
Y1585000D03*
X955000D03*
X945000D03*
X923500Y1579800D03*
X920000Y1600000D03*
X975000Y1595000D03*
Y1605000D03*
Y1585000D03*
X960000Y1700000D03*
Y1720000D03*
X933000Y1704000D03*
X951500Y1658000D03*
X952000Y1678000D03*
X980000Y1700000D03*
Y1720000D03*
X963500Y1675000D03*
Y1657000D03*
X960000Y1740000D03*
Y1760000D03*
X940000D03*
X933000Y1736500D03*
X925500Y1738000D03*
X960000Y1780000D03*
X980000D03*
Y1740000D03*
Y1760000D03*
X960000Y1860000D03*
X940000D03*
X960000Y1800000D03*
X940000D03*
X920000D03*
X940000Y1820000D03*
X960000D03*
X940000Y1840000D03*
X960000D03*
X920000D03*
X980000Y1860000D03*
Y1800000D03*
Y1820000D03*
Y1840000D03*
X987992Y1903534D03*
X920000Y1920000D03*
X940000D03*
X960000D03*
Y1940000D03*
X940000D03*
X920000D03*
X919000Y1868047D03*
X960000Y1880000D03*
X940000D03*
X920000D03*
X960000Y1900000D03*
X940000D03*
X920000D03*
X980000Y1920000D03*
Y1940000D03*
X980018Y1897856D03*
X932559Y1986626D03*
X952559D03*
X960000Y1960000D03*
X940000D03*
X920000D03*
Y1980000D03*
X940000D03*
X960000D03*
X972559Y1986626D03*
X980000Y1960000D03*
Y1980000D03*
X1031902Y43616D03*
X1020000Y40000D03*
X1000000D03*
X1031902Y23616D03*
X1030018Y5500D03*
X1010018D03*
X990018D03*
X1000000Y20000D03*
X1020000D03*
Y120000D03*
X1000000D03*
X1031902Y63616D03*
Y103616D03*
Y83616D03*
X1000000Y60000D03*
X1020000D03*
X1000000Y100000D03*
X1020000D03*
Y80000D03*
X1000000D03*
X989330Y168376D03*
X992992Y172077D03*
X1003031D03*
X1006732Y168376D03*
X1008070Y163376D03*
X1031902Y143616D03*
Y123616D03*
Y163616D03*
X1020000Y140000D03*
Y160000D03*
Y180000D03*
X1031902Y183616D03*
X1000000Y240000D03*
X1020000D03*
X1031902Y263616D03*
X1020000Y260000D03*
X1000000D03*
X1031902Y223616D03*
Y203616D03*
Y243616D03*
X1000000Y200000D03*
X1020000D03*
Y220000D03*
X1000000D03*
X1031902Y303616D03*
Y283616D03*
Y323616D03*
X1000000Y280000D03*
X1020000D03*
X1000000Y300000D03*
X1020000D03*
X1000000Y320000D03*
X1020000D03*
X1031902Y403616D03*
X1020000Y400000D03*
X1000000D03*
X1031902Y383616D03*
Y363616D03*
Y343616D03*
X1020000Y340000D03*
X1000000D03*
Y360000D03*
X1020000D03*
Y380000D03*
X1000000D03*
X1031902Y483616D03*
X1000000Y480000D03*
X1020000D03*
X1031902Y443616D03*
Y423616D03*
Y463616D03*
X1000000Y420000D03*
X1020000D03*
X1000000Y440000D03*
X1020000D03*
X1000000Y460000D03*
X1020000D03*
X1031902Y523616D03*
Y503616D03*
Y543616D03*
X1000000Y500000D03*
X1020000D03*
X1000000Y520000D03*
X1020000D03*
X1000000Y540000D03*
X1020000D03*
X1031902Y623616D03*
X1000000Y620000D03*
X1020000D03*
X1031902Y603616D03*
Y583616D03*
Y563616D03*
X1020000Y560000D03*
X1000000D03*
X1020000Y580000D03*
X1000000D03*
X1020000Y600000D03*
X1000000D03*
X989330Y691998D03*
X992992Y695699D03*
X1003031D03*
X1006732Y691998D03*
X1008070Y686998D03*
X1031902Y683616D03*
Y663616D03*
Y643616D03*
X1000000Y640000D03*
X1020000D03*
Y660000D03*
Y680000D03*
Y700000D03*
X1000000Y740000D03*
X1020000D03*
X1000000Y760000D03*
X1020000D03*
X1031902Y763616D03*
Y743616D03*
Y723616D03*
Y703616D03*
X1000000Y720000D03*
X1020000D03*
X1031902Y843616D03*
X1000000Y840000D03*
X1020000D03*
X1031902Y823616D03*
Y803616D03*
Y783616D03*
X1000000Y780000D03*
X1020000D03*
X1000000Y800000D03*
X1020000D03*
X1000000Y820000D03*
X1020000D03*
X1000000Y920000D03*
X1020000D03*
X1031902Y903616D03*
Y883616D03*
Y863616D03*
X1000000Y860000D03*
X1020000D03*
X1000000Y880000D03*
X1020000D03*
X1000000Y900000D03*
X1020000D03*
X1031902Y983616D03*
X1000000Y980000D03*
X1020000D03*
X1031902Y963616D03*
Y943616D03*
Y923616D03*
X1020000Y940000D03*
X1000000D03*
Y960000D03*
X1020000D03*
X1031902Y1063616D03*
X1020000Y1060000D03*
X1031902Y1043616D03*
Y1023616D03*
Y1003616D03*
X1020000Y1000000D03*
X1000000D03*
Y1020000D03*
X1020000D03*
Y1040000D03*
X1000000D03*
X989330Y1087667D03*
X992992Y1091368D03*
X1003031D03*
X1006732Y1087667D03*
X1008070Y1082667D03*
X1031902Y1123616D03*
X1000000Y1140000D03*
X1020000D03*
X1031902Y1103616D03*
Y1083616D03*
X1020000Y1080000D03*
Y1100000D03*
X999922Y1102598D03*
X1000000Y1120000D03*
X1020000D03*
X1031902Y1143616D03*
Y1183616D03*
Y1163616D03*
X1000000Y1160000D03*
X1020000D03*
Y1180000D03*
X1000000D03*
X1031902Y1203616D03*
X1020000Y1200000D03*
X1000000D03*
Y1220000D03*
X1020000Y1240000D03*
X1000000D03*
X1020000Y1260000D03*
X1000000D03*
X1031902Y1283616D03*
X1020000Y1280000D03*
X1000000D03*
X1031902Y1263616D03*
Y1243616D03*
Y1223616D03*
X1020000Y1220000D03*
X1031902Y1343616D03*
X1020000Y1340000D03*
X1000000D03*
X1031902Y1323616D03*
Y1303616D03*
X1020000Y1300000D03*
X1000000D03*
X1020000Y1320000D03*
X1000000D03*
X986200Y1409000D03*
X994600Y1414100D03*
X990300Y1412500D03*
X1031902Y1363616D03*
Y1383616D03*
X1020000Y1360000D03*
X1000000D03*
Y1380000D03*
X1020000D03*
Y1400000D03*
X1000000D03*
X994898Y1646102D03*
X992500Y1636000D03*
X991602Y1622500D03*
X1000000Y1700000D03*
X1020000Y1720000D03*
X1000000D03*
X995102Y1676102D03*
X995000Y1656102D03*
Y1666102D03*
X1031902Y1785969D03*
X1000000Y1780000D03*
X1020000D03*
X1031902Y1745969D03*
Y1725969D03*
Y1765969D03*
X1000000Y1740000D03*
X1020000D03*
Y1760000D03*
X1000000D03*
X1031902Y1865969D03*
Y1845969D03*
X1020000Y1860000D03*
X1000000D03*
X1031902Y1805969D03*
Y1825969D03*
X1020000Y1800000D03*
X1000000D03*
Y1820000D03*
X1020000D03*
X1000000Y1840000D03*
X1020000D03*
X989330Y1908534D03*
X992992Y1912235D03*
X1003031D03*
X1006732Y1908534D03*
X1008070Y1903534D03*
X1031902Y1925969D03*
X999469Y1923465D03*
X1020000Y1920000D03*
Y1940000D03*
X1000000D03*
X1031902Y1885969D03*
Y1905969D03*
X1020000Y1880000D03*
Y1900000D03*
X1031902Y1965969D03*
Y1945969D03*
X992559Y1986626D03*
X1012559D03*
X1031902Y1985969D03*
X1020000Y1960000D03*
X1000000D03*
Y1980000D03*
X1020000D03*
G54D20*
X31981Y1768323D03*
X135064Y213390D03*
X134941Y264178D03*
X135095Y288972D03*
X134995Y301768D03*
X135095Y625402D03*
X158500Y569500D03*
X134941Y669690D03*
X135095Y694484D03*
X134993Y707280D03*
X135095Y1030914D03*
X134941Y1075202D03*
X135095Y1099996D03*
X135001Y1112792D03*
X135095Y1436426D03*
X134935Y1480714D03*
X135095Y1505508D03*
X134995Y1518304D03*
X153700Y1633600D03*
X135065Y1835438D03*
X134895Y1905020D03*
X863441Y219890D03*
X863307Y269678D03*
X863441Y288972D03*
X863346Y301768D03*
X863441Y625402D03*
Y694484D03*
X863287Y669690D03*
X863397Y713280D03*
X863441Y1030914D03*
X863346Y1112792D03*
X863441Y1099996D03*
X863308Y1080702D03*
X863286Y1480714D03*
X863441Y1436426D03*
X863347Y1518304D03*
X863441Y1505508D03*
Y1841938D03*
X863346Y1923816D03*
X863441Y1911020D03*
X863287Y1886226D03*
G54D23*
X82087Y28858D03*
Y178464D03*
Y434370D03*
Y583976D03*
Y839882D03*
Y989488D03*
Y1245394D03*
Y1395000D03*
Y1650906D03*
Y1800512D03*
X162008Y191614D03*
Y341220D03*
Y597126D03*
Y746732D03*
Y1002638D03*
Y1152244D03*
Y1408150D03*
Y1557756D03*
Y1813662D03*
Y1963268D03*
X890354Y191614D03*
Y341220D03*
Y597126D03*
Y746732D03*
Y1002638D03*
Y1152244D03*
Y1408150D03*
Y1557756D03*
Y1813662D03*
Y1963268D03*
G54D10*
X-63741Y15000D03*
X-42339Y1008909D03*
X-63741Y1977126D03*
X25499Y1950499D03*
X1010999Y43999D03*
X1010499Y1950499D03*
X1101142Y15000D03*
Y1977126D03*
G54D14*
X11811Y571426D03*
Y949378D03*
Y1067489D03*
Y1484811D03*
Y1445441D03*
Y1862763D03*
G54D18*
X33469Y1029523D03*
X269690Y1490152D03*
G54D28*
X1023228Y1416024D03*
Y1694212D03*
G36*
G01X43453Y275788D02*
G02X23476I-9988J-8073D01*
G03X24559Y278851I-3790J3063D01*
G01Y281496D01*
G02X42370I8906J0D01*
G01Y278851D01*
G03X43453Y275788I4873J0D01*
G37*
G36*
G01X31642Y1917127D02*
G02X11665I-9989J-8073D01*
G03X12748Y1920190I-3790J3063D01*
G01Y1922835D01*
G02X30559I8906J0D01*
G01Y1920190D01*
G03X31642Y1917127I4873J0D01*
G37*
G36*
G01X143846Y12009D02*
G02X123869I-9988J-8073D01*
G03X124952Y15072I-3790J3063D01*
G01Y17717D01*
G02X142763I8905J0D01*
G01Y15072D01*
G03X143846Y12009I4873J0D01*
G37*
G36*
G01X285579Y273820D02*
G02X265602I-9988J-8073D01*
G03X266685Y276883I-3790J3063D01*
G01Y279528D01*
G02X284496I8906J0D01*
G01Y276883D01*
G03X285579Y273820I4873J0D01*
G37*
G36*
G01Y679322D02*
G02X265602I-9988J-8073D01*
G03X266685Y682385I-3790J3063D01*
G01Y685030D01*
G02X284496I8906J0D01*
G01Y682385D01*
G03X285579Y679322I4873J0D01*
G37*
G36*
G01Y1082865D02*
G02X265602I-9988J-8073D01*
G03X266685Y1085928I-3790J3063D01*
G01Y1088573D01*
G02X284496I8906J0D01*
G01Y1085928D01*
G03X285579Y1082865I4873J0D01*
G37*
G36*
G01Y1897826D02*
G02X265602I-9988J-8073D01*
G03X266685Y1900889I-3790J3063D01*
G01Y1903534D01*
G02X284496I8906J0D01*
G01Y1900889D01*
G03X285579Y1897826I4873J0D01*
G37*
G36*
G01X1008019Y157668D02*
G02X988042I-9989J-8073D01*
G03X989125Y160731I-3790J3063D01*
G01Y163376D01*
G02X1006936I8906J0D01*
G01Y160731D01*
G03X1008019Y157668I4873J0D01*
G37*
G36*
G01Y681290D02*
G02X988042I-9989J-8073D01*
G03X989125Y684353I-3790J3063D01*
G01Y686998D01*
G02X1006936I8906J0D01*
G01Y684353D01*
G03X1008019Y681290I4873J0D01*
G37*
G36*
G01Y1076959D02*
G02X988042I-9989J-8073D01*
G03X989125Y1080022I-3790J3063D01*
G01Y1082667D01*
G02X1006936I8906J0D01*
G01Y1080022D01*
G03X1008019Y1076959I4873J0D01*
G37*
G36*
G01Y1897826D02*
G02X988042I-9989J-8073D01*
G03X989125Y1900889I-3790J3063D01*
G01Y1903534D01*
G02X1006936I8906J0D01*
G01Y1900889D01*
G03X1008019Y1897826I4873J0D01*
G37*
G54D13*
X27500Y380000D03*
X27000Y440000D03*
X27500Y540000D03*
Y553500D03*
X34000Y1321000D03*
X21000Y1424500D03*
X22000Y1487000D03*
X37000Y1443500D03*
X30500Y1463500D03*
X71000Y58000D03*
X97000Y296500D03*
X111500Y276000D03*
X84500Y315000D03*
X67000Y269000D03*
X66512Y287899D03*
X46487Y360400D03*
X48822Y393916D03*
X100400Y406000D03*
X104400D03*
X107900D03*
X96900D03*
X51500Y469000D03*
X112600Y442500D03*
X98300Y443400D03*
X71000Y463500D03*
X112600Y439000D03*
X99900Y582400D03*
X61900Y584300D03*
X72900Y605400D03*
X94700Y599800D03*
X59000Y659500D03*
X49000Y638000D03*
X76500Y665000D03*
X62000Y736500D03*
X61500Y748000D03*
X51500Y730500D03*
Y757500D03*
X63100Y788800D03*
X73500Y779500D03*
X100600Y811300D03*
X104600D03*
X108100D03*
X97100D03*
X112500Y848700D03*
Y845200D03*
X98300Y850400D03*
X71000Y869000D03*
X75000Y1182500D03*
X41500Y1165500D03*
Y1178000D03*
X67500Y1191500D03*
X81500Y1213000D03*
X99100Y1219800D03*
X104500Y1217000D03*
X108000D03*
X95700Y1219700D03*
X112600Y1254300D03*
X98300Y1255900D03*
X71000Y1274500D03*
X112600Y1250800D03*
X64000Y1328500D03*
X58500Y1320500D03*
X48000Y1482000D03*
Y1505500D03*
X91125Y1565900D03*
X100500Y1622500D03*
X104500D03*
X108000D03*
X97000D03*
X98600Y1659800D03*
X71000Y1680000D03*
X170034Y31475D03*
X135500Y200500D03*
X125500Y265500D03*
X132500Y236000D03*
X128500Y248000D03*
X135064Y219602D03*
X171595Y203917D03*
X148095Y211771D03*
X171595Y218917D03*
X148095Y221220D03*
X171595Y233917D03*
X148095Y230669D03*
Y236968D03*
Y246417D03*
Y255866D03*
Y262165D03*
X126000Y293000D03*
X125000Y312000D03*
X134941Y269602D03*
X135095Y282602D03*
X134995Y307602D03*
X148095Y271614D03*
Y281063D03*
Y290511D03*
Y299960D03*
Y309409D03*
Y318858D03*
X171595Y278917D03*
Y283917D03*
X119159Y405100D03*
X163500Y423000D03*
X135095Y618614D03*
X171595Y609429D03*
X148095Y617283D03*
X171595Y624429D03*
X148095Y626732D03*
X134941Y675114D03*
X135095Y688114D03*
X171895Y639429D03*
X148095Y636181D03*
Y642480D03*
Y651929D03*
Y661378D03*
Y667677D03*
Y677126D03*
Y686575D03*
Y696023D03*
X171595Y684429D03*
Y689429D03*
X134993Y713114D03*
X148095Y705472D03*
Y714921D03*
Y724370D03*
X119534Y810975D03*
X135095Y1024126D03*
X171595Y1014941D03*
X148095Y1022795D03*
X171595Y1029941D03*
X148095Y1032244D03*
X171595Y1044941D03*
X148095Y1041693D03*
Y1047992D03*
Y1057441D03*
Y1066890D03*
X134941Y1080626D03*
X135095Y1093626D03*
X135001Y1118626D03*
X148095Y1073189D03*
Y1082638D03*
Y1092087D03*
Y1101535D03*
Y1110984D03*
Y1120433D03*
Y1129882D03*
X171595Y1089941D03*
Y1094941D03*
X119534Y1216475D03*
X135095Y1429638D03*
X171595Y1420453D03*
X148095Y1428307D03*
X134935Y1486138D03*
X135095Y1499138D03*
X171595Y1435453D03*
X148095Y1437756D03*
X171895Y1450453D03*
X148095Y1447205D03*
Y1453504D03*
Y1462953D03*
Y1472402D03*
Y1478701D03*
Y1488150D03*
Y1497599D03*
X171595Y1495453D03*
Y1500453D03*
X134995Y1524138D03*
X148095Y1507047D03*
Y1516496D03*
Y1525945D03*
Y1535394D03*
X119534Y1621975D03*
X113200Y1659800D03*
Y1656300D03*
X135065Y1841650D03*
X171595Y1825965D03*
X148095Y1833819D03*
X171595Y1840965D03*
X148095Y1843268D03*
X171595Y1855965D03*
X148095Y1852717D03*
Y1859016D03*
X134895Y1886150D03*
Y1891650D03*
Y1910650D03*
X134995Y1923650D03*
Y1929650D03*
X148095Y1868465D03*
Y1877914D03*
Y1884213D03*
Y1893662D03*
Y1903111D03*
Y1912559D03*
Y1922008D03*
Y1931457D03*
X171595Y1900965D03*
Y1905965D03*
X148095Y1940906D03*
X190500Y639713D03*
X370128Y361337D03*
X349706Y355693D03*
X356250Y349000D03*
X368500Y364500D03*
X372000D03*
X383750Y349000D03*
X391800Y355800D03*
X362000Y797000D03*
X365500D03*
X358000Y794000D03*
X377250Y779000D03*
X385250Y785700D03*
X371000Y1168000D03*
X367500D03*
X363500Y1165000D03*
X383750Y1150500D03*
X391765Y1157852D03*
X348250Y1649000D03*
X368500Y1664000D03*
X372500Y1667000D03*
X376000D03*
X356238Y1655722D03*
X876441Y262165D03*
Y255866D03*
X863307Y264102D03*
X876441Y246417D03*
Y236968D03*
Y230669D03*
Y221220D03*
Y211771D03*
X863441Y213102D03*
X899941Y233917D03*
Y218917D03*
Y203917D03*
X876441Y318858D03*
Y309409D03*
Y299960D03*
Y290511D03*
Y281063D03*
Y271614D03*
X863346Y307602D03*
X863441Y282602D03*
X899941Y283917D03*
Y278917D03*
X876441Y626732D03*
Y617283D03*
X863441Y618614D03*
X899941Y624429D03*
Y609429D03*
X876441Y661378D03*
Y651929D03*
Y642480D03*
Y636181D03*
X863287Y675114D03*
X863441Y688114D03*
X876441Y696023D03*
Y686575D03*
Y677126D03*
Y667677D03*
X899941Y684429D03*
Y639429D03*
Y689429D03*
X876441Y724370D03*
Y714921D03*
Y705472D03*
X863397Y707114D03*
X876441Y1066890D03*
Y1057441D03*
Y1047992D03*
Y1041693D03*
Y1032244D03*
Y1022795D03*
X863441Y1024126D03*
X899941Y1044941D03*
Y1029941D03*
Y1014941D03*
X876441Y1129882D03*
Y1120433D03*
Y1110984D03*
Y1101535D03*
Y1092087D03*
Y1082638D03*
Y1073189D03*
X863308Y1075126D03*
X863441Y1093626D03*
X863346Y1118626D03*
X899941Y1094941D03*
Y1089941D03*
X876441Y1428307D03*
X863441Y1429638D03*
X899941Y1420453D03*
X876441Y1478701D03*
Y1472402D03*
Y1462953D03*
Y1453504D03*
Y1447205D03*
Y1437756D03*
Y1497599D03*
Y1488150D03*
X863286Y1486138D03*
X863441Y1499138D03*
X899941Y1450453D03*
Y1435453D03*
Y1500453D03*
Y1495453D03*
X876441Y1535394D03*
Y1525945D03*
Y1516496D03*
Y1507047D03*
X863347Y1524138D03*
X876441Y1859016D03*
Y1852717D03*
Y1843268D03*
Y1833819D03*
X863441Y1835150D03*
X899941Y1855965D03*
Y1840965D03*
Y1825965D03*
X876441Y1912559D03*
Y1903111D03*
Y1893662D03*
Y1884213D03*
Y1877914D03*
Y1868465D03*
X863287Y1891650D03*
X863441Y1904650D03*
X876441Y1931457D03*
Y1922008D03*
X863346Y1929650D03*
X899941Y1905965D03*
Y1900965D03*
X876441Y1940906D03*
G54D24*
X97400Y366600D03*
X97000Y772100D03*
X96100Y1176700D03*
X88076Y1575924D03*
X43935Y1957215D03*
X824335Y365915D03*
Y771415D03*
Y1176915D03*
Y1582415D03*
X774989Y1955708D03*
G54D25*
X95849Y361564D03*
X87900Y1173300D03*
X56875Y1954250D03*
X182000Y949000D03*
X292200Y1688900D03*
X295800D03*
X374300Y81400D03*
X378100Y81500D03*
X414281Y820751D03*
X421000Y812750D03*
X420743Y1215266D03*
X414274Y1223246D03*
X421000Y1713750D03*
X414299Y1721750D03*
X815375Y362750D03*
Y768250D03*
Y1173750D03*
X816625Y1579250D03*
X780214Y1953257D03*
G54D27*
X145900Y408500D03*
X147100Y814200D03*
X146700Y1219600D03*
X143500Y1625500D03*
X196665Y35585D03*
G54D15*
X24500Y619093D03*
Y606544D03*
Y694733D03*
Y682135D03*
Y669537D03*
Y644340D03*
Y631741D03*
Y763825D03*
Y732329D03*
Y719730D03*
Y707332D03*
Y848664D03*
Y836266D03*
Y823667D03*
Y811069D03*
Y798470D03*
Y776423D03*
Y911856D03*
Y899258D03*
Y886509D03*
Y873861D03*
Y861263D03*
Y1133365D03*
Y1095769D03*
Y1108368D03*
Y1208955D03*
Y1196357D03*
Y1183758D03*
Y1171160D03*
Y1158562D03*
Y1145963D03*
Y1278247D03*
Y1265648D03*
Y1253050D03*
Y1221554D03*
Y1350888D03*
Y1338289D03*
Y1325691D03*
Y1313092D03*
Y1290845D03*
Y1401081D03*
Y1388483D03*
Y1375884D03*
Y1363286D03*
Y1566907D03*
Y1554308D03*
Y1529111D03*
Y1541710D03*
Y1639348D03*
Y1626749D03*
Y1614151D03*
Y1601552D03*
Y1588954D03*
Y1702531D03*
Y1689932D03*
Y1677334D03*
Y1762373D03*
Y1749775D03*
Y1737176D03*
Y1724578D03*
X109038Y62310D03*
X109000Y81106D03*
X109160Y105900D03*
X67500Y124088D03*
X108917Y150188D03*
X109044Y467822D03*
X109000Y486618D03*
X109138Y505912D03*
X67500Y529600D03*
X108917Y555700D03*
X109040Y873334D03*
X109000Y892130D03*
X109187Y911424D03*
X67500Y935111D03*
X109000Y961212D03*
X109040Y1278846D03*
X109000Y1297642D03*
X109133Y1316936D03*
X67500Y1340624D03*
X109000Y1366724D03*
X109040Y1684358D03*
X109000Y1703154D03*
X109137Y1722448D03*
X67500Y1757886D03*
X109030Y1778736D03*
X194500Y236902D03*
X190600Y1045226D03*
X190400Y1462536D03*
X194620Y1859298D03*
X921400Y235002D03*
X919000Y639715D03*
X922900Y1048050D03*
X919000Y1450734D03*
Y1856251D03*
G54D26*
X87075Y768250D03*
%LPC*%
G75*
G54D30*
G01X-90900Y-277455D02*
Y-294955D01*
X-82166D01*
G01X-69033Y-283289D02*
Y-294955D01*
G01Y-278622D02*
X-69470Y-278330D01*
Y-277747D01*
X-69033Y-277455D01*
X-68596Y-277747D01*
Y-278330D01*
X-69033Y-278622D01*
G01X-54590Y-299330D02*
X-53061Y-300497D01*
X-51315Y-300788D01*
X-49787Y-300497D01*
X-48476Y-299039D01*
X-47603Y-296997D01*
Y-283289D01*
G01Y-285622D02*
X-48476Y-284455D01*
X-49787Y-283580D01*
X-51315Y-283289D01*
X-53061Y-283872D01*
X-54153Y-285038D01*
X-55027Y-287080D01*
X-55463Y-289122D01*
X-55245Y-290872D01*
X-54371Y-292914D01*
X-53061Y-294372D01*
X-51315Y-294955D01*
X-50005Y-294663D01*
X-48476Y-293497D01*
X-47603Y-292331D01*
G01X-37745Y-294955D02*
Y-277455D01*
G01Y-285913D02*
X-36653Y-284455D01*
X-35561Y-283580D01*
X-33815Y-283289D01*
X-32505Y-283580D01*
X-30976Y-284747D01*
X-30321Y-286497D01*
Y-294955D01*
G01X-16533Y-277455D02*
Y-294955D01*
G01X-19590Y-283289D02*
X-13476D01*
G01X-2745Y-294955D02*
Y-283289D01*
G01Y-286205D02*
X-1871Y-284747D01*
X-561Y-283580D01*
X1185Y-283289D01*
X2713Y-283580D01*
X4024Y-284747D01*
X4679Y-286788D01*
Y-294955D01*
G01X18467Y-283289D02*
Y-294955D01*
G01Y-278622D02*
X18030Y-278330D01*
Y-277747D01*
X18467Y-277455D01*
X18904Y-277747D01*
Y-278330D01*
X18467Y-278622D01*
G01X32255Y-294955D02*
Y-283289D01*
G01Y-286205D02*
X33129Y-284747D01*
X34439Y-283580D01*
X36185Y-283289D01*
X37713Y-283580D01*
X39024Y-284747D01*
X39679Y-286788D01*
Y-294955D01*
G01X50410Y-299330D02*
X51939Y-300497D01*
X53685Y-300788D01*
X55213Y-300497D01*
X56524Y-299039D01*
X57397Y-296997D01*
Y-283289D01*
G01Y-285622D02*
X56524Y-284455D01*
X55213Y-283580D01*
X53685Y-283289D01*
X51939Y-283872D01*
X50847Y-285038D01*
X49973Y-287080D01*
X49537Y-289122D01*
X49755Y-290872D01*
X50629Y-292914D01*
X51939Y-294372D01*
X53685Y-294955D01*
X54995Y-294663D01*
X56524Y-293497D01*
X57397Y-292331D01*
G01X84100Y-294955D02*
Y-277455D01*
X89340D01*
X91087Y-278330D01*
X92397Y-280372D01*
X92834Y-282705D01*
X92397Y-285038D01*
X91305Y-286788D01*
X89340Y-287664D01*
X84100D01*
G01X101164Y-294955D02*
Y-277455D01*
X105530D01*
X107277Y-278330D01*
X108587Y-279497D01*
X109679Y-281246D01*
X110552Y-283289D01*
X110770Y-286205D01*
X110552Y-289122D01*
X109679Y-291164D01*
X108587Y-292914D01*
X107277Y-294080D01*
X105530Y-294955D01*
X101164D01*
G01X119100D02*
Y-277455D01*
X124340D01*
X126087Y-278330D01*
X127397Y-280372D01*
X127834Y-282705D01*
X127397Y-285038D01*
X126305Y-286788D01*
X124340Y-287664D01*
X119100D01*
G01X142713Y-285622D02*
X143587Y-284747D01*
X144242Y-283289D01*
X144679Y-281246D01*
X144242Y-279497D01*
X143369Y-278330D01*
X141840Y-277455D01*
X135945D01*
Y-294955D01*
X143150D01*
X144679Y-293789D01*
X145552Y-292038D01*
X145989Y-289997D01*
X145552Y-287955D01*
X144242Y-286205D01*
X142713Y-285622D01*
X135945D01*
G01X171600Y-294955D02*
Y-277455D01*
X176840D01*
X178587Y-278330D01*
X179897Y-280372D01*
X180334Y-282705D01*
X179897Y-285038D01*
X178805Y-286788D01*
X176840Y-287664D01*
X171600D01*
G01X188008Y-277455D02*
X193467Y-294955D01*
X198926Y-277455D01*
G01X210967D02*
Y-294955D01*
G01X205945Y-277455D02*
X215989D01*
G01X21540Y-249955D02*
Y-232455D01*
X27217Y-247038D01*
X32894Y-232455D01*
Y-249955D01*
G01X44717D02*
X43407Y-249663D01*
X42097Y-248497D01*
X41223Y-246455D01*
X40787Y-244122D01*
X41223Y-241788D01*
X42097Y-239747D01*
X43407Y-238580D01*
X44717Y-238289D01*
X46027Y-238580D01*
X47337Y-239747D01*
X48210Y-241788D01*
X48429Y-244122D01*
X48210Y-246455D01*
X47337Y-248497D01*
X46027Y-249663D01*
X44717Y-249955D01*
G01X66147Y-232455D02*
Y-249955D01*
G01Y-247331D02*
X65274Y-248789D01*
X63963Y-249663D01*
X62435Y-249955D01*
X60689Y-249372D01*
X59379Y-247914D01*
X58505Y-246164D01*
X58287Y-244122D01*
X58505Y-242080D01*
X59379Y-240330D01*
X60689Y-238872D01*
X62435Y-238289D01*
X63963Y-238580D01*
X65055Y-239164D01*
X66147Y-240330D01*
G01X76442Y-242080D02*
X83429D01*
X82774Y-240038D01*
X81682Y-238872D01*
X80154Y-238289D01*
X78625Y-238580D01*
X77315Y-239455D01*
X76442Y-241497D01*
X76005Y-243247D01*
Y-244997D01*
X76442Y-246747D01*
X77534Y-248497D01*
X78844Y-249663D01*
X80372Y-249955D01*
X81900Y-249372D01*
X83429Y-247622D01*
G01X97217Y-249955D02*
Y-232455D01*
G01X252500Y-249955D02*
Y-232455D01*
X257740D01*
X259487Y-233330D01*
X260797Y-235372D01*
X261234Y-237705D01*
X260797Y-240038D01*
X259705Y-241788D01*
X257740Y-242664D01*
X252500D01*
G01X279170Y-233914D02*
X277860Y-233038D01*
X276332Y-232455D01*
X274585D01*
X272620Y-233330D01*
X271092Y-234788D01*
X270000Y-236539D01*
X269127Y-239455D01*
X268908Y-242080D01*
X269345Y-244705D01*
X270000Y-246455D01*
X271310Y-248205D01*
X272839Y-249372D01*
X274367Y-249955D01*
X275895D01*
X277424Y-249372D01*
X278734Y-248497D01*
X279826Y-247331D01*
G01X293613Y-240622D02*
X294487Y-239747D01*
X295142Y-238289D01*
X295579Y-236246D01*
X295142Y-234497D01*
X294269Y-233330D01*
X292740Y-232455D01*
X286845D01*
Y-249955D01*
X294050D01*
X295579Y-248789D01*
X296452Y-247038D01*
X296889Y-244997D01*
X296452Y-242955D01*
X295142Y-241205D01*
X293613Y-240622D01*
X286845D01*
G01X302817Y-255788D02*
X315917D01*
G01X321845Y-249955D02*
Y-232455D01*
X331889Y-249955D01*
Y-232455D01*
G01X344367Y-249955D02*
X342620Y-249663D01*
X341092Y-248497D01*
X339782Y-246747D01*
X338908Y-244705D01*
X338472Y-242372D01*
Y-240038D01*
X338908Y-237705D01*
X339782Y-235663D01*
X341092Y-233914D01*
X342620Y-232747D01*
X344367Y-232455D01*
X346113Y-232747D01*
X347642Y-233914D01*
X348952Y-235663D01*
X349826Y-237705D01*
X350262Y-240038D01*
Y-242372D01*
X349826Y-244705D01*
X348952Y-246747D01*
X347642Y-248497D01*
X346113Y-249663D01*
X344367Y-249955D01*
G01X265617Y-294955D02*
Y-277455D01*
X262997Y-280955D01*
G01Y-294955D02*
X268237D01*
G01X278314Y-292331D02*
X279623Y-293789D01*
X281152Y-294663D01*
X283117Y-294955D01*
X285082Y-294372D01*
X286610Y-293205D01*
X287702Y-291164D01*
X287920Y-288830D01*
X287484Y-286497D01*
X286392Y-285038D01*
X284863Y-283872D01*
X283335Y-283580D01*
X281807Y-283872D01*
X279842Y-285038D01*
X280497Y-277455D01*
X286392D01*
G01X296469Y-287664D02*
X297997Y-285622D01*
X299307Y-284455D01*
X301054Y-283872D01*
X302582Y-284455D01*
X303674Y-285622D01*
X304547Y-287372D01*
X304765Y-289413D01*
X304547Y-291164D01*
X303674Y-292914D01*
X302363Y-294372D01*
X300835Y-294955D01*
X299089Y-294372D01*
X297560Y-292622D01*
X296687Y-289997D01*
X296469Y-287080D01*
X296905Y-283289D01*
X297560Y-281246D01*
X298652Y-279205D01*
X300180Y-277747D01*
X301709Y-277455D01*
X303237Y-278038D01*
X304329Y-279497D01*
G01X313969Y-287664D02*
X315497Y-285622D01*
X316807Y-284455D01*
X318554Y-283872D01*
X320082Y-284455D01*
X321174Y-285622D01*
X322047Y-287372D01*
X322265Y-289413D01*
X322047Y-291164D01*
X321174Y-292914D01*
X319863Y-294372D01*
X318335Y-294955D01*
X316589Y-294372D01*
X315060Y-292622D01*
X314187Y-289997D01*
X313969Y-287080D01*
X314405Y-283289D01*
X315060Y-281246D01*
X316152Y-279205D01*
X317680Y-277747D01*
X319209Y-277455D01*
X320737Y-278038D01*
X321829Y-279497D01*
G01X331905Y-292914D02*
X333434Y-294372D01*
X335180Y-294955D01*
X336927Y-294372D01*
X338455Y-292622D01*
X339547Y-289997D01*
X339984Y-287372D01*
Y-284164D01*
X339547Y-281539D01*
X338455Y-279205D01*
X337145Y-278038D01*
X335617Y-277455D01*
X333870Y-278038D01*
X332560Y-279205D01*
X331687Y-280955D01*
X331250Y-283289D01*
X331687Y-285330D01*
X332779Y-287372D01*
X334089Y-288539D01*
X335617Y-288830D01*
X337363Y-288247D01*
X338674Y-286788D01*
X339984Y-284164D01*
G01X395208Y-232455D02*
X400667Y-249955D01*
X406126Y-232455D01*
G01X422534Y-249955D02*
X413800D01*
Y-232455D01*
X422534D01*
G01X419040Y-240913D02*
X413800D01*
G01X431300Y-249955D02*
Y-232455D01*
X436759D01*
X438505Y-233330D01*
X439597Y-234497D01*
X440034Y-236830D01*
X439597Y-239164D01*
X438287Y-240622D01*
X436759Y-241497D01*
X431300D01*
G01X436759D02*
X440034Y-249955D01*
G01X453167Y-250538D02*
X452730Y-250247D01*
Y-249663D01*
X453167Y-249372D01*
X453604Y-249663D01*
Y-250247D01*
X453167Y-250538D01*
G01X426917Y-294955D02*
Y-277455D01*
X424297Y-280955D01*
G01Y-294955D02*
X429537D01*
G01X528750Y-232455D02*
Y-249955D01*
X537484D01*
G01X554547D02*
Y-238289D01*
G01Y-240330D02*
X553674Y-239164D01*
X552363Y-238580D01*
X550835Y-238289D01*
X549307Y-238872D01*
X547997Y-240038D01*
X547123Y-241788D01*
X546687Y-244122D01*
X547123Y-246455D01*
X547997Y-248205D01*
X549307Y-249372D01*
X550835Y-249955D01*
X552363Y-249663D01*
X553674Y-248789D01*
X554547Y-247622D01*
G01X563532Y-255205D02*
X564842Y-255788D01*
X566589Y-255205D01*
X567680Y-254039D01*
X568554Y-252580D01*
X569863Y-247914D01*
X572702Y-238289D01*
G01X565715D02*
X569863Y-247914D01*
G01X582342Y-242080D02*
X589329D01*
X588674Y-240038D01*
X587582Y-238872D01*
X586054Y-238289D01*
X584525Y-238580D01*
X583215Y-239455D01*
X582342Y-241497D01*
X581905Y-243247D01*
Y-244997D01*
X582342Y-246747D01*
X583434Y-248497D01*
X584744Y-249663D01*
X586272Y-249955D01*
X587800Y-249372D01*
X589329Y-247622D01*
G01X600060Y-249955D02*
Y-238289D01*
G01Y-240622D02*
X601152Y-239455D01*
X602244Y-238580D01*
X603772Y-238289D01*
X604863Y-238580D01*
X606174Y-239455D01*
G01X607484Y-277455D02*
Y-294955D01*
X598750D01*
G01X586054D02*
X585617Y-291164D01*
X584962Y-287955D01*
X584089Y-285038D01*
X582997Y-281830D01*
X581250Y-277455D01*
X589984D01*
G01X566807Y-286205D02*
X562440D01*
Y-291455D01*
X563750Y-293205D01*
X565279Y-294372D01*
X567462Y-294955D01*
X569645Y-294372D01*
X571174Y-293205D01*
X572484Y-291455D01*
X573357Y-289413D01*
X573794Y-287080D01*
Y-285038D01*
X573357Y-283289D01*
X572484Y-281246D01*
X571174Y-279497D01*
X569864Y-278330D01*
X568117Y-277455D01*
X566589D01*
X564842Y-278038D01*
X563532Y-279205D01*
G01X555639Y-294955D02*
Y-277455D01*
X545595Y-294955D01*
Y-277455D01*
G01X537920Y-294955D02*
Y-277455D01*
X533554D01*
X531807Y-278330D01*
X530497Y-279497D01*
X529405Y-281246D01*
X528532Y-283289D01*
X528314Y-286205D01*
X528532Y-289122D01*
X529405Y-291164D01*
X530497Y-292914D01*
X531807Y-294080D01*
X533554Y-294955D01*
X537920D01*
G01X670864Y-249955D02*
Y-232455D01*
X675230D01*
X676977Y-233330D01*
X678287Y-234497D01*
X679379Y-236246D01*
X680252Y-238289D01*
X680470Y-241205D01*
X680252Y-244122D01*
X679379Y-246164D01*
X678287Y-247914D01*
X676977Y-249080D01*
X675230Y-249955D01*
X670864D01*
G01X689892Y-242080D02*
X696879D01*
X696224Y-240038D01*
X695132Y-238872D01*
X693604Y-238289D01*
X692075Y-238580D01*
X690765Y-239455D01*
X689892Y-241497D01*
X689455Y-243247D01*
Y-244997D01*
X689892Y-246747D01*
X690984Y-248497D01*
X692294Y-249663D01*
X693822Y-249955D01*
X695350Y-249372D01*
X696879Y-247622D01*
G01X707392Y-247914D02*
X708484Y-249080D01*
X710012Y-249955D01*
X711322D01*
X712632Y-249372D01*
X713505Y-248497D01*
X713942Y-247331D01*
X713724Y-245580D01*
X712850Y-244705D01*
X708920Y-242955D01*
X708047Y-240913D01*
X708484Y-239455D01*
X709357Y-238580D01*
X710667Y-238289D01*
X711977Y-238580D01*
X713287Y-239455D01*
G01X728167Y-238289D02*
Y-249955D01*
G01Y-233622D02*
X727730Y-233330D01*
Y-232747D01*
X728167Y-232455D01*
X728604Y-232747D01*
Y-233330D01*
X728167Y-233622D01*
G01X742610Y-254330D02*
X744139Y-255497D01*
X745885Y-255788D01*
X747413Y-255497D01*
X748724Y-254039D01*
X749597Y-251997D01*
Y-238289D01*
G01Y-240622D02*
X748724Y-239455D01*
X747413Y-238580D01*
X745885Y-238289D01*
X744139Y-238872D01*
X743047Y-240038D01*
X742173Y-242080D01*
X741737Y-244122D01*
X741955Y-245872D01*
X742829Y-247914D01*
X744139Y-249372D01*
X745885Y-249955D01*
X747195Y-249663D01*
X748724Y-248497D01*
X749597Y-247331D01*
G01X759455Y-249955D02*
Y-238289D01*
G01Y-241205D02*
X760329Y-239747D01*
X761639Y-238580D01*
X763385Y-238289D01*
X764913Y-238580D01*
X766224Y-239747D01*
X766879Y-241788D01*
Y-249955D01*
G01X777392Y-242080D02*
X784379D01*
X783724Y-240038D01*
X782632Y-238872D01*
X781104Y-238289D01*
X779575Y-238580D01*
X778265Y-239455D01*
X777392Y-241497D01*
X776955Y-243247D01*
Y-244997D01*
X777392Y-246747D01*
X778484Y-248497D01*
X779794Y-249663D01*
X781322Y-249955D01*
X782850Y-249372D01*
X784379Y-247622D01*
G01X795110Y-249955D02*
Y-238289D01*
G01Y-240622D02*
X796202Y-239455D01*
X797294Y-238580D01*
X798822Y-238289D01*
X799913Y-238580D01*
X801224Y-239455D01*
G01X660367Y-277455D02*
X663423Y-294955D01*
X666917Y-277455D01*
X670410Y-294955D01*
X673467Y-277455D01*
G01X680050Y-294955D02*
Y-277455D01*
X685290D01*
X687037Y-278330D01*
X688347Y-280372D01*
X688784Y-282705D01*
X688347Y-285038D01*
X687255Y-286788D01*
X685290Y-287664D01*
X680050D01*
G01X697332Y-294955D02*
Y-277455D01*
G01X706502D02*
Y-294955D01*
G01Y-286205D02*
X697332D01*
G01X716579Y-289122D02*
X722255D01*
G01X732769Y-294955D02*
Y-277455D01*
X741065D01*
G01X738009Y-285913D02*
X732769D01*
G01X750050Y-277455D02*
Y-294955D01*
X758784D01*
G01X771917D02*
X770170Y-294663D01*
X768642Y-293497D01*
X767332Y-291747D01*
X766458Y-289705D01*
X766022Y-287372D01*
Y-285038D01*
X766458Y-282705D01*
X767332Y-280663D01*
X768642Y-278914D01*
X770170Y-277747D01*
X771917Y-277455D01*
X773663Y-277747D01*
X775192Y-278914D01*
X776502Y-280663D01*
X777376Y-282705D01*
X777812Y-285038D01*
Y-287372D01*
X777376Y-289705D01*
X776502Y-291747D01*
X775192Y-293497D01*
X773663Y-294663D01*
X771917Y-294955D01*
G01X785050D02*
Y-277455D01*
X790509D01*
X792255Y-278330D01*
X793347Y-279497D01*
X793784Y-281830D01*
X793347Y-284164D01*
X792037Y-285622D01*
X790509Y-286497D01*
X785050D01*
G01X790509D02*
X793784Y-294955D01*
G01X801458D02*
X806917Y-277455D01*
X812376Y-294955D01*
G01X810410Y-288830D02*
X803423D01*
G01X841867Y-294955D02*
Y-277455D01*
X839247Y-280955D01*
G01Y-294955D02*
X844487D01*
G01X859367D02*
Y-277455D01*
X856747Y-280955D01*
G01Y-294955D02*
X861987D01*
G01X872937Y-295538D02*
X880797Y-277455D01*
G01X894367Y-294955D02*
Y-277455D01*
X891747Y-280955D01*
G01Y-294955D02*
X896987D01*
G01X907719Y-287664D02*
X909247Y-285622D01*
X910557Y-284455D01*
X912304Y-283872D01*
X913832Y-284455D01*
X914924Y-285622D01*
X915797Y-287372D01*
X916015Y-289413D01*
X915797Y-291164D01*
X914924Y-292914D01*
X913613Y-294372D01*
X912085Y-294955D01*
X910339Y-294372D01*
X908810Y-292622D01*
X907937Y-289997D01*
X907719Y-287080D01*
X908155Y-283289D01*
X908810Y-281246D01*
X909902Y-279205D01*
X911430Y-277747D01*
X912959Y-277455D01*
X914487Y-278038D01*
X915579Y-279497D01*
G01X925437Y-295538D02*
X933297Y-277455D01*
G01X942719Y-280372D02*
X944029Y-278622D01*
X945557Y-277747D01*
X947304Y-277455D01*
X949487Y-278038D01*
X951015Y-279497D01*
X951452Y-281246D01*
X951234Y-282997D01*
X950360Y-284455D01*
X945994Y-287372D01*
X944029Y-289413D01*
X942719Y-292331D01*
X942282Y-294955D01*
X951452D01*
G01X964367Y-277455D02*
X962620Y-278038D01*
X961310Y-279497D01*
X960437Y-281246D01*
X959782Y-283580D01*
X959564Y-286205D01*
X959782Y-288830D01*
X960437Y-291164D01*
X961310Y-292914D01*
X962620Y-294372D01*
X964367Y-294955D01*
X966113Y-294372D01*
X967424Y-292914D01*
X968297Y-291164D01*
X968952Y-288830D01*
X969170Y-286205D01*
X968952Y-283580D01*
X968297Y-281246D01*
X967424Y-279497D01*
X966113Y-278038D01*
X964367Y-277455D01*
G01X981867Y-294955D02*
Y-277455D01*
X979247Y-280955D01*
G01Y-294955D02*
X984487D01*
G01X995219Y-287664D02*
X996747Y-285622D01*
X998057Y-284455D01*
X999804Y-283872D01*
X1001332Y-284455D01*
X1002424Y-285622D01*
X1003297Y-287372D01*
X1003515Y-289413D01*
X1003297Y-291164D01*
X1002424Y-292914D01*
X1001113Y-294372D01*
X999585Y-294955D01*
X997839Y-294372D01*
X996310Y-292622D01*
X995437Y-289997D01*
X995219Y-287080D01*
X995655Y-283289D01*
X996310Y-281246D01*
X997402Y-279205D01*
X998930Y-277747D01*
X1000459Y-277455D01*
X1001987Y-278038D01*
X1003079Y-279497D01*
G01X889564Y-249955D02*
Y-232455D01*
X893930D01*
X895677Y-233330D01*
X896987Y-234497D01*
X898079Y-236246D01*
X898952Y-238289D01*
X899170Y-241205D01*
X898952Y-244122D01*
X898079Y-246164D01*
X896987Y-247914D01*
X895677Y-249080D01*
X893930Y-249955D01*
X889564D01*
G01X915797D02*
Y-238289D01*
G01Y-240330D02*
X914924Y-239164D01*
X913613Y-238580D01*
X912085Y-238289D01*
X910557Y-238872D01*
X909247Y-240038D01*
X908373Y-241788D01*
X907937Y-244122D01*
X908373Y-246455D01*
X909247Y-248205D01*
X910557Y-249372D01*
X912085Y-249955D01*
X913613Y-249663D01*
X914924Y-248789D01*
X915797Y-247622D01*
G01X929367Y-232455D02*
Y-249955D01*
G01X926310Y-238289D02*
X932424D01*
G01X943592Y-242080D02*
X950579D01*
X949924Y-240038D01*
X948832Y-238872D01*
X947304Y-238289D01*
X945775Y-238580D01*
X944465Y-239455D01*
X943592Y-241497D01*
X943155Y-243247D01*
Y-244997D01*
X943592Y-246747D01*
X944684Y-248497D01*
X945994Y-249663D01*
X947522Y-249955D01*
X949050Y-249372D01*
X950579Y-247622D01*
G54D29*
G01X-106883Y-224955D02*
Y-304955D01*
G01Y-260455D02*
X1019417D01*
G01X-106883Y-304955D02*
X1019417D01*
G01X-110883Y-208955D02*
G02I-12000J0D01*
G01X-116033D02*
G02I-6850J0D01*
G01X-122883Y-224955D02*
Y-192955D01*
G01X-106883Y-208955D02*
X-138883D01*
G01X-106883Y-224955D02*
X1019417D01*
G01X231917D02*
Y-304955D01*
G01X369417Y-224955D02*
Y-304955D01*
G01X484417Y-224955D02*
Y-304955D01*
G01X651917Y-224955D02*
Y-304955D01*
G01X821917Y-224955D02*
Y-304955D01*
G01X1019417Y-224955D02*
Y-304955D01*
G01X1047417Y-208955D02*
G02I-12000J0D01*
G01X1042267D02*
G02I-6850J0D01*
G01X1035417Y-224955D02*
Y-192955D01*
G01X1051417Y-208955D02*
X1019417D01*
M02*
